FILE_TYPE = MACRO_DRAWING;
SET COLOR_WIRE YELLOW;
SET COLOR_PROP ORANGE;
SET COLOR_DOT WHITE;
SET COLOR_ARC YELLOW;
SET COLOR_BODY GREEN;
SET COLOR_NOTE PURPLE;
SET PROP_DISPLAY VALUE;
SET PAGE_NUMBER P186;
FORCEADD ISL99390FRZTR5935..1
(-6175 4450);
FORCEPROP 1 LAST LOCATION PU4
J 0
(-6475 5325);
DISPLAY 0.489362 (-6475 5325);
PAINT SKYBLUE (-6475 5325);
FORCEPROP 0 LAST $SEC 1
J 0
(-6475 5475);
DISPLAY 0.680851 (-6475 5475);
PAINT MONO (-6475 5475);
DISPLAY INVISIBLE (-6475 5475);
FORCEPROP 0 LAST CDS_SEC 1
J 0
(-6475 5475);
DISPLAY 1.021277 (-6475 5475);
DISPLAY INVISIBLE (-6475 5475);
FORCEPROP 0 LASTPIN (-5775 4000) $PN 2
J 0
(-5765 4010);
DISPLAY 0.489362 (-5765 4010);
PAINT MONO (-5765 4010);
FORCEPROP 0 LASTPIN (-5775 4800) $PN 33
J 0
(-5765 4810);
DISPLAY 0.489362 (-5765 4810);
PAINT MONO (-5765 4810);
FORCEPROP 0 LASTPIN (-6625 4200) $PN 31
J 2
(-6635 4210);
DISPLAY 0.489362 (-6635 4210);
PAINT MONO (-6635 4210);
FORCEPROP 0 LASTPIN (-6625 4600) $PN 35
J 2
(-6635 4610);
DISPLAY 0.489362 (-6635 4610);
PAINT MONO (-6635 4610);
FORCEPROP 0 LASTPIN (-5775 4150) $PN 6
J 0
(-5765 4160);
DISPLAY 0.489362 (-5765 4160);
PAINT MONO (-5765 4160);
FORCEPROP 0 LASTPIN (-5775 4100) $PN 41
J 0
(-5765 4110);
DISPLAY 0.489362 (-5765 4110);
PAINT MONO (-5765 4110);
FORCEPROP 0 LASTPIN (-6625 4450) $PN 38
J 2
(-6635 4460);
DISPLAY 0.489362 (-6635 4460);
PAINT MONO (-6635 4460);
FORCEPROP 0 LASTPIN (-6625 4150) $PN 37
J 2
(-6635 4160);
DISPLAY 0.489362 (-6635 4160);
PAINT MONO (-6635 4160);
FORCEPROP 0 LASTPIN (-5775 3950) $PN 5
J 0
(-5765 3960);
DISPLAY 0.489362 (-5765 3960);
PAINT MONO (-5765 3960);
FORCEPROP 0 LASTPIN (-5775 3900) $PN 7_9-20_24
J 0
(-5765 3910);
DISPLAY 0.489362 (-5765 3910);
PAINT MONO (-5765 3910);
FORCEPROP 0 LASTPIN (-5775 3850) $PN 40
J 0
(-5765 3860);
DISPLAY 0.489362 (-5765 3860);
PAINT MONO (-5765 3860);
FORCEPROP 0 LASTPIN (-5775 4550) $PN 32
J 0
(-5765 4560);
DISPLAY 0.489362 (-5765 4560);
PAINT MONO (-5765 4560);
FORCEPROP 0 LASTPIN (-6625 5100) $PN 4
J 2
(-6635 5110);
DISPLAY 0.489362 (-6635 5110);
PAINT MONO (-6635 5110);
FORCEPROP 0 LASTPIN (-6625 3850) $PN 34
J 2
(-6635 3860);
DISPLAY 0.489362 (-6635 3860);
PAINT MONO (-6635 3860);
FORCEPROP 0 LASTPIN (-6625 4350) $PN 39
J 2
(-6635 4360);
DISPLAY 0.489362 (-6635 4360);
PAINT MONO (-6635 4360);
FORCEPROP 0 LASTPIN (-5775 4450) $PN 10_19
J 0
(-5765 4460);
DISPLAY 0.489362 (-5765 4460);
PAINT MONO (-5765 4460);
FORCEPROP 0 LASTPIN (-6625 3950) $PN 36
J 2
(-6635 3960);
DISPLAY 0.489362 (-6635 3960);
PAINT MONO (-6635 3960);
FORCEPROP 0 LASTPIN (-6625 4800) $PN 3
J 2
(-6635 4810);
DISPLAY 0.489362 (-6635 4810);
PAINT MONO (-6635 4810);
FORCEPROP 0 LASTPIN (-5775 5100) $PN 25_29
J 0
(-5765 5110);
DISPLAY 0.489362 (-5765 5110);
PAINT MONO (-5765 5110);
FORCEPROP 0 LASTPIN (-5775 5050) $PN 30
J 0
(-5765 5060);
DISPLAY 0.489362 (-5765 5060);
PAINT MONO (-5765 5060);
FORCEPROP 0 LASTPIN (-5775 4200) $PN 1
J 0
(-5765 4210);
DISPLAY 0.489362 (-5765 4210);
PAINT MONO (-5765 4210);
FORCEPROP 2 LAST PART_TYPE SMLF
J 0
(-6475 5425);
DISPLAY 1.021277 (-6475 5425);
FORCEPROP 1 LAST MATERIAL IC
J 0
(-6475 5175);
DISPLAY 0.489362 (-6475 5175);
PAINT SKYBLUE (-6475 5175);
FORCEPROP 2 LAST VALUE ISL99390FRZ-TR5935
J 0
(-6475 5375);
DISPLAY 0.489362 (-6475 5375);
PAINT SKYBLUE (-6475 5375);
FORCEPROP 1 LAST PART_NUMBER AL099390004
J 0
(-6475 5250);
DISPLAY 0.489362 (-6475 5250);
PAINT SKYBLUE (-6475 5250);
FORCEPROP 1 LAST NEEDS_NO_SIZE TRUE
J 0
(-6175 4450);
DISPLAY 0.723404 (-6175 4450);
PAINT GREEN (-6175 4450);
DISPLAY INVISIBLE (-6175 4450);
FORCEPROP 1 LAST CDS_LMAN_SYM_OUTLINE -300,700,250,-650
J 0
(-6175 4450);
DISPLAY 0.468085 (-6175 4450);
PAINT GREEN (-6175 4450);
DISPLAY INVISIBLE (-6175 4450);
FORCEPROP 2 LAST CDS_LIB pure_quanta
J 0
(-6175 4450);
DISPLAY INVISIBLE (-6175 4450);
FORCEPROP 1 LAST PATH I1
J 0
(-6175 4450);
DISPLAY 0.723404 (-6175 4450);
PAINT GREEN (-6175 4450);
DISPLAY INVISIBLE (-6175 4450);
FORCEADD OFFPAGE..1
(-7275 3850);
FORCEPROP 2 LAST $XR0 186 
J 0
(-7557 3850);
DISPLAY 0.638298 (-7557 3850);
PAINT MONO (-7557 3850);
FORCEPROP 1 LAST OFFPAGE TRUE
J 0
(-6950 3725);
DISPLAY 0.872340 (-6950 3725);
PAINT GREEN (-6950 3725);
DISPLAY INVISIBLE (-6950 3725);
FORCEPROP 1 LAST COMMENT_BODY TRUE
J 0
(-7150 3750);
DISPLAY 0.872340 (-7150 3750);
PAINT GREEN (-7150 3750);
DISPLAY INVISIBLE (-7150 3750);
FORCEPROP 2 LAST CDS_LIB standard
J 2
(-7275 3850);
DISPLAY INVISIBLE (-7275 3850);
FORCEPROP 2 LAST PATH I10
J 2
(-7325 3925);
DISPLAY 1.021277 (-7325 3925);
DISPLAY INVISIBLE (-7325 3925);
FORCEADD Q_CAPP..1
(-2475 2900);
FORCEPROP 1 LAST LOCATION PC276
J 0
(-2425 3000);
DISPLAY 0.489362 (-2425 3000);
PAINT SKYBLUE (-2425 3000);
FORCEPROP 0 LAST $SEC 1
J 0
(-2425 3025);
DISPLAY 0.680851 (-2425 3025);
PAINT MONO (-2425 3025);
DISPLAY INVISIBLE (-2425 3025);
FORCEPROP 0 LAST CDS_SEC 1
J 0
(-2425 3025);
DISPLAY 1.021277 (-2425 3025);
DISPLAY INVISIBLE (-2425 3025);
FORCEPROP 1 LASTPIN (-2475 3000) $PN 1
J 0
(-2465 2985);
DISPLAY 0.489362 (-2465 2985);
PAINT MONO (-2465 2985);
FORCEPROP 1 LASTPIN (-2475 2800) $PN 2
J 0
(-2465 2785);
DISPLAY 0.489362 (-2465 2785);
PAINT MONO (-2465 2785);
FORCEPROP 1 LAST VALUE 220UF
J 0
(-2425 2950);
DISPLAY 0.489362 (-2425 2950);
PAINT SKYBLUE (-2425 2950);
FORCEPROP 1 LAST TOLERANCE 20%
J 0
(-2425 2900);
DISPLAY 0.489362 (-2425 2900);
PAINT SKYBLUE (-2425 2900);
FORCEPROP 1 LAST VOLTAGE 4V
J 0
(-2425 2850);
DISPLAY 0.489362 (-2425 2850);
PAINT SKYBLUE (-2425 2850);
FORCEPROP 1 LAST MATERIAL SPCAP
J 0
(-2425 2800);
DISPLAY 0.489362 (-2425 2800);
PAINT SKYBLUE (-2425 2800);
FORCEPROP 1 LAST PACK_TYPE SMLF
J 0
(-2425 2750);
DISPLAY 0.489362 (-2425 2750);
PAINT SKYBLUE (-2425 2750);
FORCEPROP 1 LAST PART_NUMBER CH122KM8801
J 0
(-2425 2700);
DISPLAY 0.489362 (-2425 2700);
PAINT SKYBLUE (-2425 2700);
FORCEPROP 1 LAST PATH I106
J 0
(-2425 3050);
DISPLAY 0.978723 (-2425 3050);
DISPLAY INVISIBLE (-2425 3050);
FORCEPROP 2 LAST CDS_LIB pure_quanta
J 0
(-2475 2900);
DISPLAY INVISIBLE (-2475 2900);
FORCEADD Q_CAPP..1
(-2800 2900);
FORCEPROP 1 LAST LOCATION PC275
J 0
(-2750 3000);
DISPLAY 0.489362 (-2750 3000);
PAINT SKYBLUE (-2750 3000);
FORCEPROP 0 LAST $SEC 1
J 0
(-2750 3025);
DISPLAY 0.680851 (-2750 3025);
PAINT MONO (-2750 3025);
DISPLAY INVISIBLE (-2750 3025);
FORCEPROP 0 LAST CDS_SEC 1
J 0
(-2750 3025);
DISPLAY 1.021277 (-2750 3025);
DISPLAY INVISIBLE (-2750 3025);
FORCEPROP 1 LASTPIN (-2800 3000) $PN 1
J 0
(-2790 2985);
DISPLAY 0.489362 (-2790 2985);
PAINT MONO (-2790 2985);
FORCEPROP 1 LASTPIN (-2800 2800) $PN 2
J 0
(-2790 2785);
DISPLAY 0.489362 (-2790 2785);
PAINT MONO (-2790 2785);
FORCEPROP 1 LAST VALUE 220UF
J 0
(-2750 2950);
DISPLAY 0.489362 (-2750 2950);
PAINT SKYBLUE (-2750 2950);
FORCEPROP 1 LAST TOLERANCE 20%
J 0
(-2750 2900);
DISPLAY 0.489362 (-2750 2900);
PAINT SKYBLUE (-2750 2900);
FORCEPROP 1 LAST VOLTAGE 4V
J 0
(-2750 2850);
DISPLAY 0.489362 (-2750 2850);
PAINT SKYBLUE (-2750 2850);
FORCEPROP 1 LAST MATERIAL SPCAP
J 0
(-2750 2800);
DISPLAY 0.489362 (-2750 2800);
PAINT SKYBLUE (-2750 2800);
FORCEPROP 1 LAST PACK_TYPE SMLF
J 0
(-2750 2750);
DISPLAY 0.489362 (-2750 2750);
PAINT SKYBLUE (-2750 2750);
FORCEPROP 1 LAST PART_NUMBER CH122KM8801
J 0
(-2750 2700);
DISPLAY 0.489362 (-2750 2700);
PAINT SKYBLUE (-2750 2700);
FORCEPROP 1 LAST PATH I107
J 0
(-2750 3050);
DISPLAY 0.978723 (-2750 3050);
DISPLAY INVISIBLE (-2750 3050);
FORCEPROP 2 LAST CDS_LIB pure_quanta
J 0
(-2800 2900);
DISPLAY INVISIBLE (-2800 2900);
FORCEADD VCC_CORE..1
(-1850 3200);
FORCEPROP 3 LASTPIN (-1850 3150) SIG_NAME PVDDCR_CPU0_P1\g
J 0
(-1840 3160);
DISPLAY 0.659574 (-1840 3160);
PAINT MONO (-1840 3160);
DISPLAY INVISIBLE (-1840 3160);
FORCEPROP 1 LAST HDL_POWER PVDDCR_CPU0_P1
J 1
(-1850 3250);
DISPLAY 0.489362 (-1850 3250);
PAINT GREEN (-1850 3250);
FORCEPROP 2 LAST CDS_LIB pure_quanta_power
J 0
(-1850 3200);
DISPLAY INVISIBLE (-1850 3200);
FORCEPROP 1 LAST PATH I109
J 0
(-1800 3225);
DISPLAY 0.872340 (-1800 3225);
PAINT AQUA (-1800 3225);
DISPLAY INVISIBLE (-1800 3225);
FORCEADD Q_RES..1
(-7350 4150);
FORCEPROP 1 LAST LOCATION PR187
J 0
(-7375 4200);
DISPLAY 0.489362 (-7375 4200);
PAINT SKYBLUE (-7375 4200);
FORCEPROP 0 LAST $SEC 1
J 0
(-7350 4225);
DISPLAY 0.680851 (-7350 4225);
PAINT MONO (-7350 4225);
DISPLAY INVISIBLE (-7350 4225);
FORCEPROP 0 LAST CDS_SEC 1
J 0
(-7350 4225);
DISPLAY 1.021277 (-7350 4225);
DISPLAY INVISIBLE (-7350 4225);
FORCEPROP 1 LASTPIN (-7450 4150) $PN 1
J 0
(-7438 4162);
DISPLAY 0.489362 (-7438 4162);
PAINT MONO (-7438 4162);
FORCEPROP 1 LASTPIN (-7250 4150) $PN 2
J 0
(-7288 4162);
DISPLAY 0.489362 (-7288 4162);
PAINT MONO (-7288 4162);
FORCEPROP 1 LAST WATTAGE 1/16W
J 0
(-7250 4050);
DISPLAY 0.489362 (-7250 4050);
PAINT SKYBLUE (-7250 4050);
FORCEPROP 1 LAST MATERIAL EMPTY
J 0
(-7650 4050);
DISPLAY 0.489362 (-7650 4050);
PAINT RED (-7650 4050);
FORCEPROP 1 LAST TOLERANCE 1%
J 0
(-7225 4175);
DISPLAY 0.489362 (-7225 4175);
PAINT SKYBLUE (-7225 4175);
FORCEPROP 1 LAST VALUE 8.87K
J 2
(-7450 4175);
DISPLAY 0.489362 (-7450 4175);
PAINT SKYBLUE (-7450 4175);
FORCEPROP 1 LAST PART_NUMBER CS28872FB01
J 0
(-7650 4100);
DISPLAY 0.489362 (-7650 4100);
PAINT SKYBLUE (-7650 4100);
FORCEPROP 1 LAST PACK_TYPE 0402LF
J 0
(-7250 4100);
DISPLAY 0.489362 (-7250 4100);
PAINT SKYBLUE (-7250 4100);
FORCEPROP 2 LAST CDS_LIB pure_quanta
J 0
(-7350 4150);
DISPLAY INVISIBLE (-7350 4150);
FORCEPROP 1 LAST PATH I11
J 0
(-7400 4300);
DISPLAY 0.978723 (-7400 4300);
PAINT WHITE (-7400 4300);
DISPLAY INVISIBLE (-7400 4300);
FORCEADD UNIVERSAL_GND..1
(-1850 2525);
FORCEPROP 3 LASTPIN (-1850 2575) SIG_NAME GND\g
J 0
(-1840 2585);
DISPLAY 0.659574 (-1840 2585);
PAINT MONO (-1840 2585);
DISPLAY INVISIBLE (-1840 2585);
FORCEPROP 2 LAST CDS_LIB pure_quanta_power
J 0
(-1850 2525);
DISPLAY INVISIBLE (-1850 2525);
FORCEPROP 1 LAST PATH I110
J 0
(-1775 2525);
DISPLAY 0.872340 (-1775 2525);
PAINT AQUA (-1775 2525);
DISPLAY INVISIBLE (-1775 2525);
FORCEPROP 1 LAST HDL_POWER GND
J 1
(-1825 2450);
DISPLAY 0.872340 (-1825 2450);
PAINT GREEN (-1825 2450);
DISPLAY INVISIBLE (-1825 2450);
FORCEADD Q_CAPP..1
(-1850 2900);
FORCEPROP 1 LAST LOCATION PC279
J 0
(-1800 3000);
DISPLAY 0.489362 (-1800 3000);
PAINT SKYBLUE (-1800 3000);
FORCEPROP 0 LAST $SEC 1
J 0
(-1800 3050);
DISPLAY 0.680851 (-1800 3050);
PAINT MONO (-1800 3050);
DISPLAY INVISIBLE (-1800 3050);
FORCEPROP 0 LAST CDS_SEC 1
J 0
(-1800 3050);
DISPLAY 1.021277 (-1800 3050);
DISPLAY INVISIBLE (-1800 3050);
FORCEPROP 1 LASTPIN (-1850 3000) $PN 1
J 0
(-1840 2985);
DISPLAY 0.489362 (-1840 2985);
PAINT MONO (-1840 2985);
FORCEPROP 1 LASTPIN (-1850 2800) $PN 2
J 0
(-1840 2785);
DISPLAY 0.489362 (-1840 2785);
PAINT MONO (-1840 2785);
FORCEPROP 1 LAST PACK_TYPE SMLF
J 0
(-1800 2750);
DISPLAY 0.489362 (-1800 2750);
PAINT SKYBLUE (-1800 2750);
FORCEPROP 1 LAST VOLTAGE 4V
J 0
(-1800 2850);
DISPLAY 0.489362 (-1800 2850);
PAINT SKYBLUE (-1800 2850);
FORCEPROP 1 LAST VALUE 220UF
J 0
(-1800 2950);
DISPLAY 0.489362 (-1800 2950);
PAINT SKYBLUE (-1800 2950);
FORCEPROP 1 LAST TOLERANCE 20%
J 0
(-1800 2900);
DISPLAY 0.489362 (-1800 2900);
PAINT SKYBLUE (-1800 2900);
FORCEPROP 1 LAST MATERIAL SPCAP
J 0
(-1800 2800);
DISPLAY 0.489362 (-1800 2800);
PAINT SKYBLUE (-1800 2800);
FORCEPROP 1 LAST PART_NUMBER CH122KM8801
J 0
(-1800 2700);
DISPLAY 0.489362 (-1800 2700);
PAINT SKYBLUE (-1800 2700);
FORCEPROP 1 LAST PATH I112
J 0
(-1800 3050);
DISPLAY 0.978723 (-1800 3050);
DISPLAY INVISIBLE (-1800 3050);
FORCEPROP 2 LAST CDS_LIB pure_quanta
J 0
(-1850 2900);
DISPLAY INVISIBLE (-1850 2900);
FORCEADD Q_CAP..1
(-5525 5325);
FORCEPROP 1 LAST LOCATION PC260_1
J 0
(-5475 5425);
DISPLAY 0.489362 (-5475 5425);
PAINT SKYBLUE (-5475 5425);
FORCEPROP 0 LAST $SEC 1
J 0
(-5475 5450);
DISPLAY 0.680851 (-5475 5450);
PAINT MONO (-5475 5450);
DISPLAY INVISIBLE (-5475 5450);
FORCEPROP 0 LAST CDS_SEC 1
J 0
(-5475 5450);
DISPLAY 1.021277 (-5475 5450);
DISPLAY INVISIBLE (-5475 5450);
FORCEPROP 1 LASTPIN (-5525 5425) $PN 1
J 0
(-5515 5405);
DISPLAY 0.489362 (-5515 5405);
PAINT MONO (-5515 5405);
FORCEPROP 1 LASTPIN (-5525 5225) $PN 2
J 0
(-5515 5205);
DISPLAY 0.489362 (-5515 5205);
PAINT MONO (-5515 5205);
FORCEPROP 1 LAST PART_NUMBER CH4104K1B00
J 0
(-5475 5175);
DISPLAY 0.489362 (-5475 5175);
PAINT SKYBLUE (-5475 5175);
FORCEPROP 1 LAST MATERIAL X7R
J 0
(-5475 5225);
DISPLAY 0.489362 (-5475 5225);
PAINT SKYBLUE (-5475 5225);
FORCEPROP 1 LAST TOLERANCE 10%
J 0
(-5475 5275);
DISPLAY 0.489362 (-5475 5275);
PAINT SKYBLUE (-5475 5275);
FORCEPROP 1 LAST VALUE 0.1UF
J 0
(-5475 5375);
DISPLAY 0.489362 (-5475 5375);
PAINT SKYBLUE (-5475 5375);
FORCEPROP 1 LAST VOLTAGE 25V
J 0
(-5475 5325);
DISPLAY 0.489362 (-5475 5325);
PAINT SKYBLUE (-5475 5325);
FORCEPROP 1 LAST PACK_TYPE 0402
J 0
(-5475 5125);
DISPLAY 0.489362 (-5475 5125);
PAINT SKYBLUE (-5475 5125);
FORCEPROP 2 LAST CDS_LIB pure_quanta
J 0
(-5525 5325);
DISPLAY INVISIBLE (-5525 5325);
FORCEPROP 1 LAST PATH I113
J 0
(-5475 5475);
DISPLAY 0.978723 (-5475 5475);
PAINT WHITE (-5475 5475);
DISPLAY INVISIBLE (-5475 5475);
FORCEADD Q_CAP..1
(-5525 2575);
FORCEPROP 1 LAST LOCATION PC261_2
J 0
(-5475 2675);
DISPLAY 0.489362 (-5475 2675);
PAINT SKYBLUE (-5475 2675);
FORCEPROP 0 LAST $SEC 1
J 0
(-5475 2725);
DISPLAY 0.680851 (-5475 2725);
PAINT MONO (-5475 2725);
DISPLAY INVISIBLE (-5475 2725);
FORCEPROP 0 LAST CDS_SEC 1
J 0
(-5475 2725);
DISPLAY 1.021277 (-5475 2725);
DISPLAY INVISIBLE (-5475 2725);
FORCEPROP 1 LASTPIN (-5525 2675) $PN 1
J 0
(-5515 2655);
DISPLAY 0.489362 (-5515 2655);
PAINT MONO (-5515 2655);
FORCEPROP 1 LASTPIN (-5525 2475) $PN 2
J 0
(-5515 2455);
DISPLAY 0.489362 (-5515 2455);
PAINT MONO (-5515 2455);
FORCEPROP 1 LAST PACK_TYPE 0402
J 0
(-5475 2375);
DISPLAY 0.489362 (-5475 2375);
PAINT SKYBLUE (-5475 2375);
FORCEPROP 1 LAST MATERIAL X7R
J 0
(-5475 2475);
DISPLAY 0.489362 (-5475 2475);
PAINT SKYBLUE (-5475 2475);
FORCEPROP 1 LAST TOLERANCE 10%
J 0
(-5475 2525);
DISPLAY 0.489362 (-5475 2525);
PAINT SKYBLUE (-5475 2525);
FORCEPROP 1 LAST VALUE 0.1UF
J 0
(-5475 2625);
DISPLAY 0.489362 (-5475 2625);
PAINT SKYBLUE (-5475 2625);
FORCEPROP 1 LAST PART_NUMBER CH4104K1B00
J 0
(-5475 2425);
DISPLAY 0.489362 (-5475 2425);
PAINT SKYBLUE (-5475 2425);
FORCEPROP 1 LAST VOLTAGE 25V
J 0
(-5475 2575);
DISPLAY 0.489362 (-5475 2575);
PAINT SKYBLUE (-5475 2575);
FORCEPROP 2 LAST CDS_LIB pure_quanta
J 0
(-5525 2575);
DISPLAY INVISIBLE (-5525 2575);
FORCEPROP 1 LAST PATH I114
J 0
(-5475 2725);
DISPLAY 0.978723 (-5475 2725);
PAINT WHITE (-5475 2725);
DISPLAY INVISIBLE (-5475 2725);
FORCEADD Q_CAP..1
(-7625 2050);
FORCEPROP 1 LAST LOCATION PC257
J 0
(-7575 2150);
DISPLAY 0.489362 (-7575 2150);
PAINT SKYBLUE (-7575 2150);
FORCEPROP 0 LAST $SEC 1
J 0
(-7575 2200);
DISPLAY 0.680851 (-7575 2200);
PAINT MONO (-7575 2200);
DISPLAY INVISIBLE (-7575 2200);
FORCEPROP 0 LAST CDS_SEC 1
J 0
(-7575 2200);
DISPLAY 1.021277 (-7575 2200);
DISPLAY INVISIBLE (-7575 2200);
FORCEPROP 1 LASTPIN (-7625 2150) $PN 1
J 0
(-7615 2130);
DISPLAY 0.489362 (-7615 2130);
PAINT MONO (-7615 2130);
FORCEPROP 1 LASTPIN (-7625 1950) $PN 2
J 0
(-7615 1930);
DISPLAY 0.489362 (-7615 1930);
PAINT MONO (-7615 1930);
FORCEPROP 1 LAST MATERIAL X6S
J 0
(-7575 1950);
DISPLAY 0.489362 (-7575 1950);
PAINT SKYBLUE (-7575 1950);
FORCEPROP 1 LAST TOLERANCE 10%
J 0
(-7575 2000);
DISPLAY 0.489362 (-7575 2000);
PAINT SKYBLUE (-7575 2000);
FORCEPROP 1 LAST VALUE 2.2UF
J 0
(-7575 2100);
DISPLAY 0.489362 (-7575 2100);
PAINT SKYBLUE (-7575 2100);
FORCEPROP 1 LAST PART_NUMBER CH5222KEB01
J 0
(-7575 1900);
DISPLAY 0.489362 (-7575 1900);
PAINT SKYBLUE (-7575 1900);
FORCEPROP 1 LAST VOLTAGE 10V
J 0
(-7575 2050);
DISPLAY 0.489362 (-7575 2050);
PAINT SKYBLUE (-7575 2050);
FORCEPROP 1 LAST PACK_TYPE C0402
J 0
(-7575 1850);
DISPLAY 0.489362 (-7575 1850);
PAINT SKYBLUE (-7575 1850);
FORCEPROP 2 LAST CDS_LIB pure_quanta
J 0
(-7625 2050);
DISPLAY INVISIBLE (-7625 2050);
FORCEPROP 1 LAST PATH I115
J 0
(-7575 2200);
DISPLAY 0.978723 (-7575 2200);
PAINT WHITE (-7575 2200);
DISPLAY INVISIBLE (-7575 2200);
FORCEADD UNIVERSAL_GND..1
(-7625 1850);
FORCEPROP 3 LASTPIN (-7625 1900) SIG_NAME GND\g
J 0
(-7615 1910);
DISPLAY 0.659574 (-7615 1910);
PAINT MONO (-7615 1910);
DISPLAY INVISIBLE (-7615 1910);
FORCEPROP 2 LAST CDS_LIB pure_quanta_power
J 0
(-7625 1850);
DISPLAY INVISIBLE (-7625 1850);
FORCEPROP 1 LAST PATH I116
J 0
(-7550 1850);
DISPLAY 0.872340 (-7550 1850);
PAINT AQUA (-7550 1850);
DISPLAY INVISIBLE (-7550 1850);
FORCEPROP 1 LAST HDL_POWER GND
J 1
(-7600 1775);
DISPLAY 0.872340 (-7600 1775);
PAINT GREEN (-7600 1775);
DISPLAY INVISIBLE (-7600 1775);
FORCEADD UNIVERSAL_GND..1
(-7275 2350);
FORCEPROP 3 LASTPIN (-7275 2400) SIG_NAME GND\g
J 0
(-7265 2410);
DISPLAY 0.659574 (-7265 2410);
PAINT MONO (-7265 2410);
DISPLAY INVISIBLE (-7265 2410);
FORCEPROP 2 LAST CDS_LIB pure_quanta_power
J 0
(-7275 2350);
DISPLAY INVISIBLE (-7275 2350);
FORCEPROP 1 LAST PATH I117
J 0
(-7200 2350);
DISPLAY 0.872340 (-7200 2350);
PAINT AQUA (-7200 2350);
DISPLAY INVISIBLE (-7200 2350);
FORCEPROP 1 LAST HDL_POWER GND
J 1
(-7250 2275);
DISPLAY 0.872340 (-7250 2275);
PAINT GREEN (-7250 2275);
DISPLAY INVISIBLE (-7250 2275);
FORCEADD Q_RES..2
(-7625 2600);
FORCEPROP 1 LAST LOCATION PR186
J 0
(-7580 2725);
DISPLAY 0.489362 (-7580 2725);
PAINT SKYBLUE (-7580 2725);
FORCEPROP 0 LAST $SEC 1
J 0
(-7575 2775);
DISPLAY 0.680851 (-7575 2775);
PAINT MONO (-7575 2775);
DISPLAY INVISIBLE (-7575 2775);
FORCEPROP 0 LAST CDS_SEC 1
J 0
(-7575 2775);
DISPLAY 1.021277 (-7575 2775);
DISPLAY INVISIBLE (-7575 2775);
FORCEPROP 1 LASTPIN (-7625 2700) $PN 1
J 0
(-7620 2662);
DISPLAY 0.489362 (-7620 2662);
PAINT MONO (-7620 2662);
FORCEPROP 1 LASTPIN (-7625 2500) $PN 2
J 0
(-7620 2510);
DISPLAY 0.489362 (-7620 2510);
PAINT MONO (-7620 2510);
FORCEPROP 1 LAST WATTAGE 1/16W
J 0
(-7575 2575);
DISPLAY 0.489362 (-7575 2575);
PAINT SKYBLUE (-7575 2575);
FORCEPROP 1 LAST MATERIAL CHIP
J 0
(-7575 2525);
DISPLAY 0.489362 (-7575 2525);
PAINT SKYBLUE (-7575 2525);
FORCEPROP 1 LAST TOLERANCE 1%
J 0
(-7575 2625);
DISPLAY 0.489362 (-7575 2625);
PAINT SKYBLUE (-7575 2625);
FORCEPROP 1 LAST VALUE 2.2
J 0
(-7575 2675);
DISPLAY 0.489362 (-7575 2675);
PAINT SKYBLUE (-7575 2675);
FORCEPROP 1 LAST PART_NUMBER CS-2202FB00
J 0
(-7575 2475);
DISPLAY 0.489362 (-7575 2475);
PAINT SKYBLUE (-7575 2475);
FORCEPROP 1 LAST PACK_TYPE 0402LF
J 0
(-7575 2425);
DISPLAY 0.489362 (-7575 2425);
PAINT SKYBLUE (-7575 2425);
FORCEPROP 2 LAST CDS_LIB pure_quanta
J 0
(-7625 2600);
DISPLAY INVISIBLE (-7625 2600);
FORCEPROP 1 LAST PATH I118
J 0
(-7575 2775);
DISPLAY 0.978723 (-7575 2775);
PAINT WHITE (-7575 2775);
DISPLAY INVISIBLE (-7575 2775);
FORCEADD Q_CAP..1
(-7275 2625);
FORCEPROP 1 LAST LOCATION PC259_C0P1_2
J 0
(-7225 2725);
DISPLAY 0.489362 (-7225 2725);
PAINT SKYBLUE (-7225 2725);
FORCEPROP 0 LAST $SEC 1
J 0
(-7225 2775);
DISPLAY 0.680851 (-7225 2775);
PAINT MONO (-7225 2775);
DISPLAY INVISIBLE (-7225 2775);
FORCEPROP 0 LAST CDS_SEC 1
J 0
(-7225 2775);
DISPLAY 1.021277 (-7225 2775);
DISPLAY INVISIBLE (-7225 2775);
FORCEPROP 1 LASTPIN (-7275 2725) $PN 1
J 0
(-7265 2705);
DISPLAY 0.489362 (-7265 2705);
PAINT MONO (-7265 2705);
FORCEPROP 1 LASTPIN (-7275 2525) $PN 2
J 0
(-7265 2505);
DISPLAY 0.489362 (-7265 2505);
PAINT MONO (-7265 2505);
FORCEPROP 1 LAST MATERIAL X6S
J 0
(-7225 2525);
DISPLAY 0.489362 (-7225 2525);
PAINT SKYBLUE (-7225 2525);
FORCEPROP 1 LAST TOLERANCE 10%
J 0
(-7225 2575);
DISPLAY 0.489362 (-7225 2575);
PAINT SKYBLUE (-7225 2575);
FORCEPROP 1 LAST VALUE 2.2UF
J 0
(-7225 2675);
DISPLAY 0.489362 (-7225 2675);
PAINT SKYBLUE (-7225 2675);
FORCEPROP 1 LAST PART_NUMBER CH5222KEB01
J 0
(-7225 2475);
DISPLAY 0.489362 (-7225 2475);
PAINT SKYBLUE (-7225 2475);
FORCEPROP 1 LAST VOLTAGE 10V
J 0
(-7225 2625);
DISPLAY 0.489362 (-7225 2625);
PAINT SKYBLUE (-7225 2625);
FORCEPROP 1 LAST PACK_TYPE C0402
J 0
(-7225 2425);
DISPLAY 0.489362 (-7225 2425);
PAINT SKYBLUE (-7225 2425);
FORCEPROP 2 LAST CDS_LIB pure_quanta
J 0
(-7275 2625);
DISPLAY INVISIBLE (-7275 2625);
FORCEPROP 1 LAST PATH I119
J 0
(-7225 2775);
DISPLAY 0.978723 (-7225 2775);
PAINT WHITE (-7225 2775);
DISPLAY INVISIBLE (-7225 2775);
FORCEADD UNIVERSAL_GND..1
(-7675 3975);
FORCEPROP 3 LASTPIN (-7675 4025) SIG_NAME GND\g
J 0
(-7665 4035);
DISPLAY 0.659574 (-7665 4035);
PAINT MONO (-7665 4035);
DISPLAY INVISIBLE (-7665 4035);
FORCEPROP 2 LAST CDS_LIB pure_quanta_power
J 0
(-7675 3975);
DISPLAY INVISIBLE (-7675 3975);
FORCEPROP 1 LAST PATH I12
J 0
(-7600 3975);
DISPLAY 0.872340 (-7600 3975);
PAINT AQUA (-7600 3975);
DISPLAY INVISIBLE (-7600 3975);
FORCEPROP 1 LAST HDL_POWER GND
J 1
(-7650 3900);
DISPLAY 0.872340 (-7650 3900);
PAINT GREEN (-7650 3900);
DISPLAY INVISIBLE (-7650 3900);
FORCEADD VCC_CORE..1
(-7625 3000);
FORCEPROP 3 LASTPIN (-7625 2950) SIG_NAME PVDDCR_CPU0_P1_PVCC\g
J 0
(-7615 2960);
DISPLAY 0.659574 (-7615 2960);
PAINT MONO (-7615 2960);
DISPLAY INVISIBLE (-7615 2960);
FORCEPROP 1 LAST HDL_POWER PVDDCR_CPU0_P1_PVCC
J 1
(-7625 3050);
DISPLAY 0.489362 (-7625 3050);
PAINT GREEN (-7625 3050);
FORCEPROP 2 LAST CDS_LIB pure_quanta_power
J 0
(-7625 3000);
DISPLAY INVISIBLE (-7625 3000);
FORCEPROP 1 LAST PATH I120
J 0
(-7575 3025);
DISPLAY 0.872340 (-7575 3025);
PAINT AQUA (-7575 3025);
DISPLAY INVISIBLE (-7575 3025);
FORCEADD Q_CAPP..1
(-3150 2900);
FORCEPROP 1 LAST LOCATION PC105
J 0
(-3100 3000);
DISPLAY 0.489362 (-3100 3000);
PAINT SKYBLUE (-3100 3000);
FORCEPROP 0 LAST $SEC 1
J 0
(-3100 3050);
DISPLAY 0.680851 (-3100 3050);
PAINT MONO (-3100 3050);
DISPLAY INVISIBLE (-3100 3050);
FORCEPROP 0 LAST CDS_SEC 1
J 0
(-3100 3050);
DISPLAY 1.021277 (-3100 3050);
DISPLAY INVISIBLE (-3100 3050);
FORCEPROP 1 LASTPIN (-3150 3000) $PN 1
J 0
(-3140 2985);
DISPLAY 0.489362 (-3140 2985);
PAINT MONO (-3140 2985);
FORCEPROP 1 LASTPIN (-3150 2800) $PN 2
J 0
(-3140 2785);
DISPLAY 0.489362 (-3140 2785);
PAINT MONO (-3140 2785);
FORCEPROP 1 LAST VOLTAGE 4V
J 0
(-3100 2850);
DISPLAY 0.489362 (-3100 2850);
PAINT SKYBLUE (-3100 2850);
FORCEPROP 1 LAST TOLERANCE 20%
J 0
(-3100 2900);
DISPLAY 0.489362 (-3100 2900);
PAINT SKYBLUE (-3100 2900);
FORCEPROP 1 LAST VALUE 220UF
J 0
(-3100 2950);
DISPLAY 0.489362 (-3100 2950);
PAINT SKYBLUE (-3100 2950);
FORCEPROP 1 LAST MATERIAL SPCAP
J 0
(-3100 2800);
DISPLAY 0.489362 (-3100 2800);
PAINT SKYBLUE (-3100 2800);
FORCEPROP 1 LAST PACK_TYPE SMLF
J 0
(-3100 2750);
DISPLAY 0.489362 (-3100 2750);
PAINT SKYBLUE (-3100 2750);
FORCEPROP 1 LAST PART_NUMBER CH122KM8801
J 0
(-3100 2700);
DISPLAY 0.489362 (-3100 2700);
PAINT SKYBLUE (-3100 2700);
FORCEPROP 1 LAST PATH I121
J 0
(-3100 3050);
DISPLAY 0.978723 (-3100 3050);
DISPLAY INVISIBLE (-3100 3050);
FORCEPROP 2 LAST CDS_LIB pure_quanta
J 0
(-3150 2900);
DISPLAY INVISIBLE (-3150 2900);
FORCEADD OFFPAGE..3
(-2150 1450);
FORCEPROP 2 LAST $XR0 188 
J 0
(-1936 1450);
DISPLAY 0.638298 (-1936 1450);
PAINT MONO (-1936 1450);
FORCEPROP 2 LAST PATH I122
J 0
(-1950 1525);
DISPLAY 1.021277 (-1950 1525);
DISPLAY INVISIBLE (-1950 1525);
FORCEPROP 1 LAST OFFPAGE TRUE
J 0
(-1825 1325);
DISPLAY 0.872340 (-1825 1325);
PAINT GREEN (-1825 1325);
DISPLAY INVISIBLE (-1825 1325);
FORCEPROP 1 LAST COMMENT_BODY TRUE
J 0
(-2200 1350);
DISPLAY 0.872340 (-2200 1350);
PAINT GREEN (-2200 1350);
DISPLAY INVISIBLE (-2200 1350);
FORCEPROP 2 LAST CDS_LIB standard
J 0
(-2150 1450);
DISPLAY INVISIBLE (-2150 1450);
FORCEADD UNIVERSAL_GND..1
(-4850 3550);
FORCEPROP 3 LASTPIN (-4850 3600) SIG_NAME GND\g
J 0
(-4840 3610);
DISPLAY 0.659574 (-4840 3610);
PAINT MONO (-4840 3610);
DISPLAY INVISIBLE (-4840 3610);
FORCEPROP 2 LAST CDS_LIB pure_quanta_power
J 0
(-4850 3550);
DISPLAY INVISIBLE (-4850 3550);
FORCEPROP 1 LAST PATH I123
J 0
(-4775 3550);
DISPLAY 0.872340 (-4775 3550);
PAINT AQUA (-4775 3550);
DISPLAY INVISIBLE (-4775 3550);
FORCEPROP 1 LAST HDL_POWER GND
J 1
(-4825 3475);
DISPLAY 0.872340 (-4825 3475);
PAINT GREEN (-4825 3475);
DISPLAY INVISIBLE (-4825 3475);
FORCEADD Q_RES..2
(-4850 3775);
FORCEPROP 1 LAST LOCATION PR485
J 0
(-4805 3900);
DISPLAY 0.489362 (-4805 3900);
PAINT SKYBLUE (-4805 3900);
FORCEPROP 0 LAST $SEC 1
J 0
(-4800 3950);
DISPLAY 0.680851 (-4800 3950);
PAINT MONO (-4800 3950);
DISPLAY INVISIBLE (-4800 3950);
FORCEPROP 0 LAST CDS_SEC 1
J 0
(-4800 3950);
DISPLAY 1.021277 (-4800 3950);
DISPLAY INVISIBLE (-4800 3950);
FORCEPROP 1 LASTPIN (-4850 3875) $PN 1
J 0
(-4845 3837);
DISPLAY 0.489362 (-4845 3837);
PAINT MONO (-4845 3837);
FORCEPROP 1 LASTPIN (-4850 3675) $PN 2
J 0
(-4845 3685);
DISPLAY 0.489362 (-4845 3685);
PAINT MONO (-4845 3685);
FORCEPROP 1 LAST PART_NUMBER CS-1504FB00
J 0
(-4810 3650);
DISPLAY 0.489362 (-4810 3650);
PAINT SKYBLUE (-4810 3650);
FORCEPROP 1 LAST MATERIAL EMPTY
J 0
(-4810 3700);
DISPLAY 0.489362 (-4810 3700);
PAINT RED (-4810 3700);
FORCEPROP 1 LAST PACK_TYPE 0402LF
J 0
(-4810 3600);
DISPLAY 0.489362 (-4810 3600);
PAINT SKYBLUE (-4810 3600);
FORCEPROP 1 LAST WATTAGE 1/8W
J 0
(-4810 3750);
DISPLAY 0.489362 (-4810 3750);
PAINT SKYBLUE (-4810 3750);
FORCEPROP 1 LAST TOLERANCE 1%
J 0
(-4805 3800);
DISPLAY 0.489362 (-4805 3800);
PAINT SKYBLUE (-4805 3800);
FORCEPROP 1 LAST VALUE 1.5
J 0
(-4805 3850);
DISPLAY 0.489362 (-4805 3850);
PAINT SKYBLUE (-4805 3850);
FORCEPROP 2 LAST CDS_LIB pure_quanta
J 0
(-4850 3775);
DISPLAY INVISIBLE (-4850 3775);
FORCEPROP 1 LAST PATH I124
J 0
(-4800 3950);
DISPLAY 0.978723 (-4800 3950);
PAINT WHITE (-4800 3950);
DISPLAY INVISIBLE (-4800 3950);
FORCEADD Q_CAP..1
(-4850 4250);
FORCEPROP 1 LAST LOCATION PC170
J 0
(-4800 4350);
DISPLAY 0.489362 (-4800 4350);
PAINT SKYBLUE (-4800 4350);
FORCEPROP 0 LAST $SEC 1
J 0
(-4800 4400);
DISPLAY 0.680851 (-4800 4400);
PAINT MONO (-4800 4400);
DISPLAY INVISIBLE (-4800 4400);
FORCEPROP 0 LAST CDS_SEC 1
J 0
(-4800 4400);
DISPLAY 1.021277 (-4800 4400);
DISPLAY INVISIBLE (-4800 4400);
FORCEPROP 1 LASTPIN (-4850 4350) $PN 1
J 0
(-4840 4330);
DISPLAY 0.489362 (-4840 4330);
PAINT MONO (-4840 4330);
FORCEPROP 1 LASTPIN (-4850 4150) $PN 2
J 0
(-4840 4130);
DISPLAY 0.489362 (-4840 4130);
PAINT MONO (-4840 4130);
FORCEPROP 1 LAST PART_NUMBER CH1566K1B09
J 0
(-4800 4100);
DISPLAY 0.489362 (-4800 4100);
PAINT SKYBLUE (-4800 4100);
FORCEPROP 1 LAST VOLTAGE 50V
J 0
(-4800 4250);
DISPLAY 0.489362 (-4800 4250);
PAINT SKYBLUE (-4800 4250);
FORCEPROP 1 LAST MATERIAL EMPTY
J 0
(-4800 4150);
DISPLAY 0.489362 (-4800 4150);
PAINT RED (-4800 4150);
FORCEPROP 1 LAST TOLERANCE 10%
J 0
(-4800 4200);
DISPLAY 0.489362 (-4800 4200);
PAINT SKYBLUE (-4800 4200);
FORCEPROP 1 LAST VALUE 560PF
J 0
(-4800 4300);
DISPLAY 0.489362 (-4800 4300);
PAINT SKYBLUE (-4800 4300);
FORCEPROP 1 LAST PACK_TYPE C0402
J 0
(-4800 4050);
DISPLAY 0.489362 (-4800 4050);
PAINT SKYBLUE (-4800 4050);
FORCEPROP 2 LAST CDS_LIB pure_quanta
J 0
(-4850 4250);
DISPLAY INVISIBLE (-4850 4250);
FORCEPROP 1 LAST PATH I125
J 0
(-4800 4400);
DISPLAY 0.978723 (-4800 4400);
PAINT WHITE (-4800 4400);
DISPLAY INVISIBLE (-4800 4400);
FORCEADD UNIVERSAL_GND..1
(-4700 775);
FORCEPROP 3 LASTPIN (-4700 825) SIG_NAME GND\g
J 0
(-4690 835);
DISPLAY 0.659574 (-4690 835);
PAINT MONO (-4690 835);
DISPLAY INVISIBLE (-4690 835);
FORCEPROP 2 LAST CDS_LIB pure_quanta_power
J 0
(-4700 775);
DISPLAY INVISIBLE (-4700 775);
FORCEPROP 1 LAST PATH I126
J 0
(-4625 775);
DISPLAY 0.872340 (-4625 775);
PAINT AQUA (-4625 775);
DISPLAY INVISIBLE (-4625 775);
FORCEPROP 1 LAST HDL_POWER GND
J 1
(-4675 700);
DISPLAY 0.872340 (-4675 700);
PAINT GREEN (-4675 700);
DISPLAY INVISIBLE (-4675 700);
FORCEADD Q_RES..2
(-4700 1000);
FORCEPROP 1 LAST LOCATION PR486
J 0
(-4655 1125);
DISPLAY 0.489362 (-4655 1125);
PAINT SKYBLUE (-4655 1125);
FORCEPROP 0 LAST $SEC 1
J 0
(-4650 1175);
DISPLAY 0.680851 (-4650 1175);
PAINT MONO (-4650 1175);
DISPLAY INVISIBLE (-4650 1175);
FORCEPROP 0 LAST CDS_SEC 1
J 0
(-4650 1175);
DISPLAY 1.021277 (-4650 1175);
DISPLAY INVISIBLE (-4650 1175);
FORCEPROP 1 LASTPIN (-4700 1100) $PN 1
J 0
(-4695 1062);
DISPLAY 0.489362 (-4695 1062);
PAINT MONO (-4695 1062);
FORCEPROP 1 LASTPIN (-4700 900) $PN 2
J 0
(-4695 910);
DISPLAY 0.489362 (-4695 910);
PAINT MONO (-4695 910);
FORCEPROP 1 LAST WATTAGE 1/8W
J 0
(-4660 975);
DISPLAY 0.489362 (-4660 975);
PAINT SKYBLUE (-4660 975);
FORCEPROP 1 LAST MATERIAL EMPTY
J 0
(-4660 925);
DISPLAY 0.489362 (-4660 925);
PAINT RED (-4660 925);
FORCEPROP 1 LAST TOLERANCE 1%
J 0
(-4655 1025);
DISPLAY 0.489362 (-4655 1025);
PAINT SKYBLUE (-4655 1025);
FORCEPROP 1 LAST VALUE 1.5
J 0
(-4655 1075);
DISPLAY 0.489362 (-4655 1075);
PAINT SKYBLUE (-4655 1075);
FORCEPROP 1 LAST PART_NUMBER CS-1504FB00
J 0
(-4660 875);
DISPLAY 0.489362 (-4660 875);
PAINT SKYBLUE (-4660 875);
FORCEPROP 1 LAST PACK_TYPE 0402LF
J 0
(-4660 825);
DISPLAY 0.489362 (-4660 825);
PAINT SKYBLUE (-4660 825);
FORCEPROP 2 LAST CDS_LIB pure_quanta
J 0
(-4700 1000);
DISPLAY INVISIBLE (-4700 1000);
FORCEPROP 1 LAST PATH I127
J 0
(-4650 1175);
DISPLAY 0.978723 (-4650 1175);
PAINT WHITE (-4650 1175);
DISPLAY INVISIBLE (-4650 1175);
FORCEADD Q_CAP..1
(-4700 1500);
FORCEPROP 1 LAST LOCATION PC173
J 0
(-4650 1600);
DISPLAY 0.489362 (-4650 1600);
PAINT SKYBLUE (-4650 1600);
FORCEPROP 0 LAST $SEC 1
J 0
(-4650 1650);
DISPLAY 0.680851 (-4650 1650);
PAINT MONO (-4650 1650);
DISPLAY INVISIBLE (-4650 1650);
FORCEPROP 0 LAST CDS_SEC 1
J 0
(-4650 1650);
DISPLAY 1.021277 (-4650 1650);
DISPLAY INVISIBLE (-4650 1650);
FORCEPROP 1 LASTPIN (-4700 1600) $PN 1
J 0
(-4690 1580);
DISPLAY 0.489362 (-4690 1580);
PAINT MONO (-4690 1580);
FORCEPROP 1 LASTPIN (-4700 1400) $PN 2
J 0
(-4690 1380);
DISPLAY 0.489362 (-4690 1380);
PAINT MONO (-4690 1380);
FORCEPROP 1 LAST MATERIAL EMPTY
J 0
(-4650 1400);
DISPLAY 0.489362 (-4650 1400);
PAINT RED (-4650 1400);
FORCEPROP 1 LAST TOLERANCE 10%
J 0
(-4650 1450);
DISPLAY 0.489362 (-4650 1450);
PAINT SKYBLUE (-4650 1450);
FORCEPROP 1 LAST VALUE 560PF
J 0
(-4650 1550);
DISPLAY 0.489362 (-4650 1550);
PAINT SKYBLUE (-4650 1550);
FORCEPROP 1 LAST PART_NUMBER CH1566K1B09
J 0
(-4650 1350);
DISPLAY 0.489362 (-4650 1350);
PAINT SKYBLUE (-4650 1350);
FORCEPROP 1 LAST VOLTAGE 50V
J 0
(-4650 1500);
DISPLAY 0.489362 (-4650 1500);
PAINT SKYBLUE (-4650 1500);
FORCEPROP 1 LAST PACK_TYPE C0402
J 0
(-4650 1300);
DISPLAY 0.489362 (-4650 1300);
PAINT SKYBLUE (-4650 1300);
FORCEPROP 2 LAST CDS_LIB pure_quanta
J 0
(-4700 1500);
DISPLAY INVISIBLE (-4700 1500);
FORCEPROP 1 LAST PATH I128
J 0
(-4650 1650);
DISPLAY 0.978723 (-4650 1650);
PAINT WHITE (-4650 1650);
DISPLAY INVISIBLE (-4650 1650);
FORCEADD OFFPAGE..3
R 2
(-4300 4200);
FORCEPROP 2 LAST $XR0 189 
J 0
(-4580 4200);
DISPLAY 0.638298 (-4580 4200);
PAINT MONO (-4580 4200);
FORCEPROP 2 LAST CDS_LIB standard
J 0
(-4300 4200);
DISPLAY INVISIBLE (-4300 4200);
FORCEPROP 1 LAST COMMENT_BODY TRUE
J 2
(-4250 4100);
DISPLAY 0.872340 (-4250 4100);
PAINT GREEN (-4250 4100);
DISPLAY INVISIBLE (-4250 4100);
FORCEPROP 2 LAST PATH I129
J 0
(-4250 4275);
DISPLAY 1.021277 (-4250 4275);
DISPLAY INVISIBLE (-4250 4275);
FORCEPROP 1 LAST OFFPAGE TRUE
J 2
(-4625 4075);
DISPLAY 0.872340 (-4625 4075);
PAINT GREEN (-4625 4075);
DISPLAY INVISIBLE (-4625 4075);
FORCEADD Q_CAP..1
(-8000 4175);
FORCEPROP 1 LAST LOCATION PC254_1
J 0
(-7950 4275);
DISPLAY 0.489362 (-7950 4275);
PAINT SKYBLUE (-7950 4275);
FORCEPROP 0 LAST $SEC 1
J 0
(-7950 4300);
DISPLAY 0.680851 (-7950 4300);
PAINT MONO (-7950 4300);
DISPLAY INVISIBLE (-7950 4300);
FORCEPROP 0 LAST CDS_SEC 1
J 0
(-7950 4300);
DISPLAY 1.021277 (-7950 4300);
DISPLAY INVISIBLE (-7950 4300);
FORCEPROP 1 LASTPIN (-8000 4275) $PN 1
J 0
(-7990 4255);
DISPLAY 0.489362 (-7990 4255);
PAINT MONO (-7990 4255);
FORCEPROP 1 LASTPIN (-8000 4075) $PN 2
J 0
(-7990 4055);
DISPLAY 0.489362 (-7990 4055);
PAINT MONO (-7990 4055);
FORCEPROP 1 LAST MATERIAL X7R
J 0
(-7950 4075);
DISPLAY 0.489362 (-7950 4075);
PAINT SKYBLUE (-7950 4075);
FORCEPROP 1 LAST TOLERANCE 10%
J 0
(-7950 4125);
DISPLAY 0.489362 (-7950 4125);
PAINT SKYBLUE (-7950 4125);
FORCEPROP 1 LAST VALUE 0.1UF
J 0
(-7950 4225);
DISPLAY 0.489362 (-7950 4225);
PAINT SKYBLUE (-7950 4225);
FORCEPROP 1 LAST PART_NUMBER CH4104K1B00
J 0
(-7950 4025);
DISPLAY 0.489362 (-7950 4025);
PAINT SKYBLUE (-7950 4025);
FORCEPROP 1 LAST VOLTAGE 25V
J 0
(-7950 4175);
DISPLAY 0.489362 (-7950 4175);
PAINT SKYBLUE (-7950 4175);
FORCEPROP 1 LAST PACK_TYPE 0402
J 0
(-7950 3975);
DISPLAY 0.489362 (-7950 3975);
PAINT SKYBLUE (-7950 3975);
FORCEPROP 2 LAST CDS_LIB pure_quanta
J 0
(-8000 4175);
DISPLAY INVISIBLE (-8000 4175);
FORCEPROP 1 LAST PATH I13
J 0
(-7950 4325);
DISPLAY 0.978723 (-7950 4325);
PAINT WHITE (-7950 4325);
DISPLAY INVISIBLE (-7950 4325);
FORCEADD Q_RES..1
R 1
(-8300 5750);
FORCEPROP 1 LAST LOCATION PR335
J 0
(-8275 5900);
DISPLAY 0.489362 (-8275 5900);
PAINT SKYBLUE (-8275 5900);
FORCEPROP 0 LAST $SEC 1
R 1
J 0
(-8275 5925);
DISPLAY 0.680851 (-8275 5925);
PAINT MONO (-8275 5925);
DISPLAY INVISIBLE (-8275 5925);
FORCEPROP 0 LAST CDS_SEC 1
R 1
J 0
(-8275 5925);
DISPLAY 1.021277 (-8275 5925);
DISPLAY INVISIBLE (-8275 5925);
FORCEPROP 1 LASTPIN (-8300 5650) $PN 1
R 1
J 0
(-8312 5662);
DISPLAY 0.787234 (-8312 5662);
PAINT MONO (-8312 5662);
DISPLAY INVISIBLE (-8312 5662);
FORCEPROP 1 LASTPIN (-8300 5850) $PN 2
R 1
J 0
(-8312 5812);
DISPLAY 0.787234 (-8312 5812);
PAINT MONO (-8312 5812);
DISPLAY INVISIBLE (-8312 5812);
FORCEPROP 1 LAST WATTAGE 1/16W
J 0
(-8275 5750);
DISPLAY 0.489362 (-8275 5750);
PAINT SKYBLUE (-8275 5750);
FORCEPROP 1 LAST MATERIAL CHIP
J 0
(-8275 5700);
DISPLAY 0.489362 (-8275 5700);
PAINT SKYBLUE (-8275 5700);
FORCEPROP 1 LAST TOLERANCE 5%
J 0
(-8275 5800);
DISPLAY 0.489362 (-8275 5800);
PAINT SKYBLUE (-8275 5800);
FORCEPROP 1 LAST VALUE 0
J 2
(-8250 5850);
DISPLAY 0.489362 (-8250 5850);
PAINT SKYBLUE (-8250 5850);
FORCEPROP 1 LAST PART_NUMBER CS00002JB38
J 0
(-8275 5650);
DISPLAY 0.489362 (-8275 5650);
PAINT SKYBLUE (-8275 5650);
FORCEPROP 1 LAST PACK_TYPE 0402LF
J 0
(-8275 5600);
DISPLAY 0.489362 (-8275 5600);
PAINT SKYBLUE (-8275 5600);
FORCEPROP 2 LAST CDS_LIB pure_quanta
J 0
(-8300 5750);
DISPLAY INVISIBLE (-8300 5750);
FORCEPROP 1 LAST PATH I130
R 1
J 0
(-8450 5700);
DISPLAY 0.978723 (-8450 5700);
PAINT WHITE (-8450 5700);
DISPLAY INVISIBLE (-8450 5700);
FORCEADD VCC_CORE..1
(-8300 5950);
FORCEPROP 3 LASTPIN (-8300 5900) SIG_NAME P5V_STBY\g
J 0
(-8290 5910);
DISPLAY 0.659574 (-8290 5910);
PAINT MONO (-8290 5910);
DISPLAY INVISIBLE (-8290 5910);
FORCEPROP 1 LAST HDL_POWER P5V_STBY
J 1
(-8300 6000);
DISPLAY 0.489362 (-8300 6000);
PAINT GREEN (-8300 6000);
FORCEPROP 2 LAST CDS_LIB pure_quanta_power
J 0
(-8300 5950);
DISPLAY INVISIBLE (-8300 5950);
FORCEPROP 1 LAST PATH I131
J 0
(-8250 5975);
DISPLAY 0.872340 (-8250 5975);
PAINT AQUA (-8250 5975);
DISPLAY INVISIBLE (-8250 5975);
FORCEADD Q_RES..1
R 1
(-7950 5750);
FORCEPROP 1 LAST LOCATION PR336
J 0
(-7900 5900);
DISPLAY 0.489362 (-7900 5900);
PAINT SKYBLUE (-7900 5900);
FORCEPROP 0 LAST $SEC 1
R 1
J 0
(-7900 5925);
DISPLAY 0.680851 (-7900 5925);
PAINT MONO (-7900 5925);
DISPLAY INVISIBLE (-7900 5925);
FORCEPROP 0 LAST CDS_SEC 1
R 1
J 0
(-7900 5925);
DISPLAY 1.021277 (-7900 5925);
DISPLAY INVISIBLE (-7900 5925);
FORCEPROP 1 LASTPIN (-7950 5650) $PN 1
R 1
J 0
(-7962 5662);
DISPLAY 0.787234 (-7962 5662);
PAINT MONO (-7962 5662);
DISPLAY INVISIBLE (-7962 5662);
FORCEPROP 1 LASTPIN (-7950 5850) $PN 2
R 1
J 0
(-7962 5812);
DISPLAY 0.787234 (-7962 5812);
PAINT MONO (-7962 5812);
DISPLAY INVISIBLE (-7962 5812);
FORCEPROP 1 LAST WATTAGE 1/16W
J 0
(-7900 5750);
DISPLAY 0.489362 (-7900 5750);
PAINT SKYBLUE (-7900 5750);
FORCEPROP 1 LAST MATERIAL EMPTY
J 0
(-7900 5700);
DISPLAY 0.489362 (-7900 5700);
PAINT RED (-7900 5700);
FORCEPROP 1 LAST TOLERANCE 5%
J 0
(-7900 5800);
DISPLAY 0.489362 (-7900 5800);
PAINT SKYBLUE (-7900 5800);
FORCEPROP 1 LAST VALUE 0
J 2
(-7875 5850);
DISPLAY 0.489362 (-7875 5850);
PAINT SKYBLUE (-7875 5850);
FORCEPROP 1 LAST PART_NUMBER CS00002JB38
J 0
(-7900 5650);
DISPLAY 0.489362 (-7900 5650);
PAINT SKYBLUE (-7900 5650);
FORCEPROP 1 LAST PACK_TYPE 0402LF
J 0
(-7900 5600);
DISPLAY 0.489362 (-7900 5600);
PAINT SKYBLUE (-7900 5600);
FORCEPROP 2 LAST CDS_LIB pure_quanta
J 0
(-7950 5750);
DISPLAY INVISIBLE (-7950 5750);
FORCEPROP 1 LAST PATH I132
R 1
J 0
(-8100 5700);
DISPLAY 0.978723 (-8100 5700);
PAINT WHITE (-8100 5700);
DISPLAY INVISIBLE (-8100 5700);
FORCEADD VCC_CORE..1
(-7950 5950);
FORCEPROP 3 LASTPIN (-7950 5900) SIG_NAME P3V3_STBY\g
J 0
(-7940 5910);
DISPLAY 0.659574 (-7940 5910);
PAINT MONO (-7940 5910);
DISPLAY INVISIBLE (-7940 5910);
FORCEPROP 1 LAST HDL_POWER P3V3_STBY
J 1
(-7950 6000);
DISPLAY 0.489362 (-7950 6000);
PAINT GREEN (-7950 6000);
FORCEPROP 2 LAST CDS_LIB pure_quanta_power
J 0
(-7950 5950);
DISPLAY INVISIBLE (-7950 5950);
FORCEPROP 1 LAST PATH I133
J 0
(-7900 5975);
DISPLAY 0.872340 (-7900 5975);
PAINT AQUA (-7900 5975);
DISPLAY INVISIBLE (-7900 5975);
FORCEADD VCC_CORE..1
(-7475 5950);
FORCEPROP 3 LASTPIN (-7475 5900) SIG_NAME PVDDCR_CPU0_P1_PVCC\g
J 0
(-7465 5910);
DISPLAY 0.659574 (-7465 5910);
PAINT MONO (-7465 5910);
DISPLAY INVISIBLE (-7465 5910);
FORCEPROP 1 LAST HDL_POWER PVDDCR_CPU0_P1_PVCC
J 1
(-7475 6000);
DISPLAY 0.489362 (-7475 6000);
PAINT GREEN (-7475 6000);
FORCEPROP 2 LAST CDS_LIB pure_quanta_power
J 0
(-7475 5950);
DISPLAY INVISIBLE (-7475 5950);
FORCEPROP 1 LAST PATH I134
J 0
(-7425 5975);
DISPLAY 0.872340 (-7425 5975);
PAINT AQUA (-7425 5975);
DISPLAY INVISIBLE (-7425 5975);
FORCEADD Q_RES..2
(-975 4275);
FORCEPROP 1 LAST LOCATION PR337
J 0
(-930 4400);
DISPLAY 0.489362 (-930 4400);
PAINT SKYBLUE (-930 4400);
FORCEPROP 0 LAST $SEC 1
J 0
(-925 4425);
DISPLAY 0.680851 (-925 4425);
PAINT MONO (-925 4425);
DISPLAY INVISIBLE (-925 4425);
FORCEPROP 0 LAST CDS_SEC 1
J 0
(-925 4425);
DISPLAY 1.021277 (-925 4425);
DISPLAY INVISIBLE (-925 4425);
FORCEPROP 1 LASTPIN (-975 4375) $PN 1
J 0
(-970 4337);
DISPLAY 0.787234 (-970 4337);
PAINT MONO (-970 4337);
DISPLAY INVISIBLE (-970 4337);
FORCEPROP 1 LASTPIN (-975 4175) $PN 2
J 0
(-970 4185);
DISPLAY 0.787234 (-970 4185);
PAINT MONO (-970 4185);
DISPLAY INVISIBLE (-970 4185);
FORCEPROP 1 LAST WATTAGE 1/16W
J 0
(-935 4250);
DISPLAY 0.489362 (-935 4250);
PAINT SKYBLUE (-935 4250);
FORCEPROP 1 LAST MATERIAL CHIP
J 0
(-935 4200);
DISPLAY 0.489362 (-935 4200);
PAINT SKYBLUE (-935 4200);
FORCEPROP 1 LAST TOLERANCE 1%
J 0
(-930 4300);
DISPLAY 0.489362 (-930 4300);
PAINT SKYBLUE (-930 4300);
FORCEPROP 1 LAST VALUE 1K
J 0
(-930 4350);
DISPLAY 0.489362 (-930 4350);
PAINT SKYBLUE (-930 4350);
FORCEPROP 1 LAST PART_NUMBER TMP_QCS21002FB24
J 0
(-935 4150);
DISPLAY 0.489362 (-935 4150);
PAINT SKYBLUE (-935 4150);
FORCEPROP 1 LAST PACK_TYPE 0402LF
J 0
(-935 4100);
DISPLAY 0.489362 (-935 4100);
PAINT SKYBLUE (-935 4100);
FORCEPROP 2 LAST CDS_LIB pure_quanta
J 0
(-975 4275);
DISPLAY INVISIBLE (-975 4275);
FORCEPROP 1 LAST PATH I135
J 0
(-925 4450);
DISPLAY 0.978723 (-925 4450);
PAINT WHITE (-925 4450);
DISPLAY INVISIBLE (-925 4450);
FORCEADD UNIVERSAL_GND..1
(-8000 3900);
FORCEPROP 3 LASTPIN (-8000 3950) SIG_NAME GND\g
J 0
(-7990 3960);
DISPLAY 0.659574 (-7990 3960);
PAINT MONO (-7990 3960);
DISPLAY INVISIBLE (-7990 3960);
FORCEPROP 2 LAST CDS_LIB pure_quanta_power
J 0
(-8000 3900);
DISPLAY INVISIBLE (-8000 3900);
FORCEPROP 1 LAST PATH I14
J 0
(-7925 3900);
DISPLAY 0.872340 (-7925 3900);
PAINT AQUA (-7925 3900);
DISPLAY INVISIBLE (-7925 3900);
FORCEPROP 1 LAST HDL_POWER GND
J 1
(-7975 3825);
DISPLAY 0.872340 (-7975 3825);
PAINT GREEN (-7975 3825);
DISPLAY INVISIBLE (-7975 3825);
FORCEADD UNIVERSAL_GND..1
(-5600 3725);
FORCEPROP 3 LASTPIN (-5600 3775) SIG_NAME GND\g
J 0
(-5590 3785);
DISPLAY 0.659574 (-5590 3785);
PAINT MONO (-5590 3785);
DISPLAY INVISIBLE (-5590 3785);
FORCEPROP 2 LAST CDS_LIB pure_quanta_power
J 0
(-5600 3725);
DISPLAY INVISIBLE (-5600 3725);
FORCEPROP 1 LAST PATH I15
J 0
(-5525 3725);
DISPLAY 0.872340 (-5525 3725);
PAINT AQUA (-5525 3725);
DISPLAY INVISIBLE (-5525 3725);
FORCEPROP 1 LAST HDL_POWER GND
J 1
(-5575 3650);
DISPLAY 0.872340 (-5575 3650);
PAINT GREEN (-5575 3650);
DISPLAY INVISIBLE (-5575 3650);
FORCEADD Q_RES..1
(-4925 4800);
FORCEPROP 1 LAST LOCATION PR189
J 0
(-4975 4850);
DISPLAY 0.489362 (-4975 4850);
PAINT SKYBLUE (-4975 4850);
FORCEPROP 0 LAST $SEC 1
J 0
(-4900 4875);
DISPLAY 0.680851 (-4900 4875);
PAINT MONO (-4900 4875);
DISPLAY INVISIBLE (-4900 4875);
FORCEPROP 0 LAST CDS_SEC 1
J 0
(-4900 4875);
DISPLAY 1.021277 (-4900 4875);
DISPLAY INVISIBLE (-4900 4875);
FORCEPROP 1 LASTPIN (-5025 4800) $PN 1
J 0
(-5013 4812);
DISPLAY 0.489362 (-5013 4812);
PAINT MONO (-5013 4812);
FORCEPROP 1 LASTPIN (-4825 4800) $PN 2
J 0
(-4863 4812);
DISPLAY 0.489362 (-4863 4812);
PAINT MONO (-4863 4812);
FORCEPROP 1 LAST PACK_TYPE 0402LF
J 0
(-4825 4700);
DISPLAY 0.489362 (-4825 4700);
PAINT SKYBLUE (-4825 4700);
FORCEPROP 1 LAST MATERIAL CHIP
J 0
(-5175 4700);
DISPLAY 0.489362 (-5175 4700);
PAINT SKYBLUE (-5175 4700);
FORCEPROP 1 LAST WATTAGE 1/16W
J 0
(-4825 4750);
DISPLAY 0.489362 (-4825 4750);
PAINT SKYBLUE (-4825 4750);
FORCEPROP 1 LAST TOLERANCE 1%
J 0
(-4825 4825);
DISPLAY 0.489362 (-4825 4825);
PAINT SKYBLUE (-4825 4825);
FORCEPROP 1 LAST VALUE 4.7
J 2
(-5025 4825);
DISPLAY 0.489362 (-5025 4825);
PAINT SKYBLUE (-5025 4825);
FORCEPROP 1 LAST PART_NUMBER CS-4702FB19
J 0
(-5175 4750);
DISPLAY 0.489362 (-5175 4750);
PAINT SKYBLUE (-5175 4750);
FORCEPROP 1 LAST PATH I16
J 0
(-4975 4950);
DISPLAY 0.978723 (-4975 4950);
PAINT WHITE (-4975 4950);
DISPLAY INVISIBLE (-4975 4950);
FORCEPROP 2 LAST CDS_LIB pure_quanta
J 0
(-4925 4800);
DISPLAY INVISIBLE (-4925 4800);
FORCEADD Q_CAP..1
(-4100 4675);
FORCEPROP 1 LAST LOCATION PC270
J 0
(-4050 4800);
DISPLAY 0.489362 (-4050 4800);
PAINT SKYBLUE (-4050 4800);
FORCEPROP 0 LAST $SEC 1
J 0
(-4050 4825);
DISPLAY 0.680851 (-4050 4825);
PAINT MONO (-4050 4825);
DISPLAY INVISIBLE (-4050 4825);
FORCEPROP 0 LAST CDS_SEC 1
J 0
(-4050 4825);
DISPLAY 1.021277 (-4050 4825);
DISPLAY INVISIBLE (-4050 4825);
FORCEPROP 1 LASTPIN (-4100 4775) $PN 1
J 0
(-4090 4755);
DISPLAY 0.489362 (-4090 4755);
PAINT MONO (-4090 4755);
FORCEPROP 1 LASTPIN (-4100 4575) $PN 2
J 0
(-4090 4555);
DISPLAY 0.489362 (-4090 4555);
PAINT MONO (-4090 4555);
FORCEPROP 1 LAST VALUE 0.22UF
J 0
(-4050 4750);
DISPLAY 0.489362 (-4050 4750);
PAINT SKYBLUE (-4050 4750);
FORCEPROP 1 LAST PART_NUMBER CH4223K1B00
J 0
(-4050 4550);
DISPLAY 0.489362 (-4050 4550);
PAINT SKYBLUE (-4050 4550);
FORCEPROP 1 LAST TOLERANCE 10%
J 0
(-4050 4650);
DISPLAY 0.489362 (-4050 4650);
PAINT SKYBLUE (-4050 4650);
FORCEPROP 1 LAST VOLTAGE 16V
J 0
(-4050 4700);
DISPLAY 0.489362 (-4050 4700);
PAINT SKYBLUE (-4050 4700);
FORCEPROP 1 LAST PACK_TYPE 0402
J 0
(-4050 4500);
DISPLAY 0.489362 (-4050 4500);
PAINT SKYBLUE (-4050 4500);
FORCEPROP 1 LAST MATERIAL X7R
J 0
(-4050 4600);
DISPLAY 0.489362 (-4050 4600);
PAINT SKYBLUE (-4050 4600);
FORCEPROP 2 LAST CDS_LIB pure_quanta
J 0
(-4100 4675);
DISPLAY INVISIBLE (-4100 4675);
FORCEPROP 1 LAST PATH I17
J 0
(-4050 4825);
DISPLAY 0.978723 (-4050 4825);
PAINT WHITE (-4050 4825);
DISPLAY INVISIBLE (-4050 4825);
FORCEADD Q_CAP..1
(-4250 5325);
FORCEPROP 1 LAST LOCATION PC268_1
J 0
(-4200 5425);
DISPLAY 0.489362 (-4200 5425);
PAINT SKYBLUE (-4200 5425);
FORCEPROP 0 LAST $SEC 1
J 0
(-4200 5450);
DISPLAY 0.680851 (-4200 5450);
PAINT MONO (-4200 5450);
DISPLAY INVISIBLE (-4200 5450);
FORCEPROP 0 LAST CDS_SEC 1
J 0
(-4200 5450);
DISPLAY 1.021277 (-4200 5450);
DISPLAY INVISIBLE (-4200 5450);
FORCEPROP 1 LASTPIN (-4250 5425) $PN 1
J 0
(-4240 5405);
DISPLAY 0.489362 (-4240 5405);
PAINT MONO (-4240 5405);
FORCEPROP 1 LASTPIN (-4250 5225) $PN 2
J 0
(-4240 5205);
DISPLAY 0.489362 (-4240 5205);
PAINT MONO (-4240 5205);
FORCEPROP 1 LAST VOLTAGE 25V
J 0
(-4200 5325);
DISPLAY 0.489362 (-4200 5325);
PAINT SKYBLUE (-4200 5325);
FORCEPROP 1 LAST PART_NUMBER CH6104KEA00
J 0
(-4200 5175);
DISPLAY 0.489362 (-4200 5175);
PAINT SKYBLUE (-4200 5175);
FORCEPROP 1 LAST PACK_TYPE C0805
J 0
(-4200 5125);
DISPLAY 0.489362 (-4200 5125);
PAINT SKYBLUE (-4200 5125);
FORCEPROP 1 LAST MATERIAL X6S
J 0
(-4200 5225);
DISPLAY 0.489362 (-4200 5225);
PAINT SKYBLUE (-4200 5225);
FORCEPROP 1 LAST TOLERANCE 10%
J 0
(-4200 5275);
DISPLAY 0.489362 (-4200 5275);
PAINT SKYBLUE (-4200 5275);
FORCEPROP 1 LAST VALUE 10UF
J 0
(-4200 5375);
DISPLAY 0.489362 (-4200 5375);
PAINT SKYBLUE (-4200 5375);
FORCEPROP 2 LAST CDS_LIB pure_quanta
J 0
(-4250 5325);
DISPLAY INVISIBLE (-4250 5325);
FORCEPROP 1 LAST PATH I18
J 0
(-4200 5475);
DISPLAY 0.978723 (-4200 5475);
PAINT WHITE (-4200 5475);
DISPLAY INVISIBLE (-4200 5475);
FORCEADD Q_CAP..1
(-4550 5325);
FORCEPROP 1 LAST LOCATION PC266_1
J 0
(-4500 5425);
DISPLAY 0.489362 (-4500 5425);
PAINT SKYBLUE (-4500 5425);
FORCEPROP 0 LAST $SEC 1
J 0
(-4500 5450);
DISPLAY 0.680851 (-4500 5450);
PAINT MONO (-4500 5450);
DISPLAY INVISIBLE (-4500 5450);
FORCEPROP 0 LAST CDS_SEC 1
J 0
(-4500 5450);
DISPLAY 1.021277 (-4500 5450);
DISPLAY INVISIBLE (-4500 5450);
FORCEPROP 1 LASTPIN (-4550 5425) $PN 1
J 0
(-4540 5405);
DISPLAY 0.489362 (-4540 5405);
PAINT MONO (-4540 5405);
FORCEPROP 1 LASTPIN (-4550 5225) $PN 2
J 0
(-4540 5205);
DISPLAY 0.489362 (-4540 5205);
PAINT MONO (-4540 5205);
FORCEPROP 1 LAST VALUE 10UF
J 0
(-4500 5375);
DISPLAY 0.489362 (-4500 5375);
PAINT SKYBLUE (-4500 5375);
FORCEPROP 1 LAST VOLTAGE 25V
J 0
(-4500 5325);
DISPLAY 0.489362 (-4500 5325);
PAINT SKYBLUE (-4500 5325);
FORCEPROP 1 LAST MATERIAL X6S
J 0
(-4500 5225);
DISPLAY 0.489362 (-4500 5225);
PAINT SKYBLUE (-4500 5225);
FORCEPROP 1 LAST TOLERANCE 10%
J 0
(-4500 5275);
DISPLAY 0.489362 (-4500 5275);
PAINT SKYBLUE (-4500 5275);
FORCEPROP 1 LAST PART_NUMBER CH6104KEA00
J 0
(-4500 5175);
DISPLAY 0.489362 (-4500 5175);
PAINT SKYBLUE (-4500 5175);
FORCEPROP 1 LAST PACK_TYPE C0805
J 0
(-4500 5125);
DISPLAY 0.489362 (-4500 5125);
PAINT SKYBLUE (-4500 5125);
FORCEPROP 2 LAST CDS_LIB pure_quanta
J 0
(-4550 5325);
DISPLAY INVISIBLE (-4550 5325);
FORCEPROP 1 LAST PATH I19
J 0
(-4500 5475);
DISPLAY 0.978723 (-4500 5475);
PAINT WHITE (-4500 5475);
DISPLAY INVISIBLE (-4500 5475);
FORCEADD Q_CAP..1
(-7300 5375);
FORCEPROP 1 LAST LOCATION PC258_C0P1_1
J 0
(-7250 5475);
DISPLAY 0.489362 (-7250 5475);
PAINT SKYBLUE (-7250 5475);
FORCEPROP 0 LAST $SEC 1
J 0
(-7250 5500);
DISPLAY 0.680851 (-7250 5500);
PAINT MONO (-7250 5500);
DISPLAY INVISIBLE (-7250 5500);
FORCEPROP 0 LAST CDS_SEC 1
J 0
(-7250 5500);
DISPLAY 1.021277 (-7250 5500);
DISPLAY INVISIBLE (-7250 5500);
FORCEPROP 1 LASTPIN (-7300 5475) $PN 1
J 0
(-7290 5455);
DISPLAY 0.489362 (-7290 5455);
PAINT MONO (-7290 5455);
FORCEPROP 1 LASTPIN (-7300 5275) $PN 2
J 0
(-7290 5255);
DISPLAY 0.489362 (-7290 5255);
PAINT MONO (-7290 5255);
FORCEPROP 1 LAST PART_NUMBER CH5222KEB01
J 0
(-7250 5225);
DISPLAY 0.489362 (-7250 5225);
PAINT SKYBLUE (-7250 5225);
FORCEPROP 1 LAST TOLERANCE 10%
J 0
(-7250 5325);
DISPLAY 0.489362 (-7250 5325);
PAINT SKYBLUE (-7250 5325);
FORCEPROP 1 LAST MATERIAL X6S
J 0
(-7250 5275);
DISPLAY 0.489362 (-7250 5275);
PAINT SKYBLUE (-7250 5275);
FORCEPROP 1 LAST VALUE 2.2UF
J 0
(-7250 5425);
DISPLAY 0.489362 (-7250 5425);
PAINT SKYBLUE (-7250 5425);
FORCEPROP 1 LAST VOLTAGE 10V
J 0
(-7250 5375);
DISPLAY 0.489362 (-7250 5375);
PAINT SKYBLUE (-7250 5375);
FORCEPROP 1 LAST PACK_TYPE C0402
J 0
(-7250 5175);
DISPLAY 0.489362 (-7250 5175);
PAINT SKYBLUE (-7250 5175);
FORCEPROP 2 LAST CDS_LIB pure_quanta
J 0
(-7300 5375);
DISPLAY INVISIBLE (-7300 5375);
FORCEPROP 1 LAST PATH I2
J 0
(-7250 5525);
DISPLAY 0.978723 (-7250 5525);
PAINT WHITE (-7250 5525);
DISPLAY INVISIBLE (-7250 5525);
FORCEADD Q_CAP..1
(-4875 5325);
FORCEPROP 1 LAST LOCATION PC264_1
J 0
(-4825 5425);
DISPLAY 0.489362 (-4825 5425);
PAINT SKYBLUE (-4825 5425);
FORCEPROP 0 LAST $SEC 1
J 0
(-4825 5450);
DISPLAY 0.680851 (-4825 5450);
PAINT MONO (-4825 5450);
DISPLAY INVISIBLE (-4825 5450);
FORCEPROP 0 LAST CDS_SEC 1
J 0
(-4825 5450);
DISPLAY 1.021277 (-4825 5450);
DISPLAY INVISIBLE (-4825 5450);
FORCEPROP 1 LASTPIN (-4875 5425) $PN 1
J 0
(-4865 5405);
DISPLAY 0.489362 (-4865 5405);
PAINT MONO (-4865 5405);
FORCEPROP 1 LASTPIN (-4875 5225) $PN 2
J 0
(-4865 5205);
DISPLAY 0.489362 (-4865 5205);
PAINT MONO (-4865 5205);
FORCEPROP 1 LAST MATERIAL X6S
J 0
(-4825 5225);
DISPLAY 0.489362 (-4825 5225);
PAINT SKYBLUE (-4825 5225);
FORCEPROP 1 LAST TOLERANCE 10%
J 0
(-4825 5275);
DISPLAY 0.489362 (-4825 5275);
PAINT SKYBLUE (-4825 5275);
FORCEPROP 1 LAST VALUE 10UF
J 0
(-4825 5375);
DISPLAY 0.489362 (-4825 5375);
PAINT SKYBLUE (-4825 5375);
FORCEPROP 1 LAST PART_NUMBER CH6104KEA00
J 0
(-4825 5175);
DISPLAY 0.489362 (-4825 5175);
PAINT SKYBLUE (-4825 5175);
FORCEPROP 1 LAST VOLTAGE 25V
J 0
(-4825 5325);
DISPLAY 0.489362 (-4825 5325);
PAINT SKYBLUE (-4825 5325);
FORCEPROP 1 LAST PACK_TYPE C0805
J 0
(-4825 5125);
DISPLAY 0.489362 (-4825 5125);
PAINT SKYBLUE (-4825 5125);
FORCEPROP 2 LAST CDS_LIB pure_quanta
J 0
(-4875 5325);
DISPLAY INVISIBLE (-4875 5325);
FORCEPROP 1 LAST PATH I20
J 0
(-4825 5475);
DISPLAY 0.978723 (-4825 5475);
PAINT WHITE (-4825 5475);
DISPLAY INVISIBLE (-4825 5475);
FORCEADD Q_CAP..1
(-5200 5325);
FORCEPROP 1 LAST LOCATION PC262_1
J 0
(-5150 5425);
DISPLAY 0.489362 (-5150 5425);
PAINT SKYBLUE (-5150 5425);
FORCEPROP 0 LAST $SEC 1
J 0
(-5150 5450);
DISPLAY 0.680851 (-5150 5450);
PAINT MONO (-5150 5450);
DISPLAY INVISIBLE (-5150 5450);
FORCEPROP 0 LAST CDS_SEC 1
J 0
(-5150 5450);
DISPLAY 1.021277 (-5150 5450);
DISPLAY INVISIBLE (-5150 5450);
FORCEPROP 1 LASTPIN (-5200 5425) $PN 1
J 0
(-5190 5405);
DISPLAY 0.489362 (-5190 5405);
PAINT MONO (-5190 5405);
FORCEPROP 1 LASTPIN (-5200 5225) $PN 2
J 0
(-5190 5205);
DISPLAY 0.489362 (-5190 5205);
PAINT MONO (-5190 5205);
FORCEPROP 1 LAST PACK_TYPE C0402
J 0
(-5150 5125);
DISPLAY 0.489362 (-5150 5125);
PAINT SKYBLUE (-5150 5125);
FORCEPROP 1 LAST MATERIAL X6S
J 0
(-5150 5225);
DISPLAY 0.489362 (-5150 5225);
PAINT SKYBLUE (-5150 5225);
FORCEPROP 1 LAST TOLERANCE 10%
J 0
(-5150 5275);
DISPLAY 0.489362 (-5150 5275);
PAINT SKYBLUE (-5150 5275);
FORCEPROP 1 LAST VALUE 1UF
J 0
(-5150 5375);
DISPLAY 0.489362 (-5150 5375);
PAINT SKYBLUE (-5150 5375);
FORCEPROP 1 LAST PART_NUMBER CH5104KEB02
J 0
(-5150 5175);
DISPLAY 0.489362 (-5150 5175);
PAINT SKYBLUE (-5150 5175);
FORCEPROP 1 LAST VOLTAGE 25V
J 0
(-5150 5325);
DISPLAY 0.489362 (-5150 5325);
PAINT SKYBLUE (-5150 5325);
FORCEPROP 2 LAST CDS_LIB pure_quanta
J 0
(-5200 5325);
DISPLAY INVISIBLE (-5200 5325);
FORCEPROP 1 LAST PATH I21
J 0
(-5150 5475);
DISPLAY 0.978723 (-5150 5475);
PAINT WHITE (-5150 5475);
DISPLAY INVISIBLE (-5150 5475);
FORCEADD UNIVERSAL_GND..1
(-4050 4975);
FORCEPROP 3 LASTPIN (-4050 5025) SIG_NAME GND\g
J 0
(-4040 5035);
DISPLAY 0.659574 (-4040 5035);
PAINT MONO (-4040 5035);
DISPLAY INVISIBLE (-4040 5035);
FORCEPROP 2 LAST CDS_LIB pure_quanta_power
J 0
(-4050 4975);
DISPLAY INVISIBLE (-4050 4975);
FORCEPROP 1 LAST PATH I23
J 0
(-3975 4975);
DISPLAY 0.872340 (-3975 4975);
PAINT AQUA (-3975 4975);
DISPLAY INVISIBLE (-3975 4975);
FORCEPROP 1 LAST HDL_POWER GND
J 1
(-4025 4900);
DISPLAY 0.872340 (-4025 4900);
PAINT GREEN (-4025 4900);
DISPLAY INVISIBLE (-4025 4900);
FORCEADD Q_INDUCTOR..1
(-2950 5525);
FORCEPROP 1 LAST LOCATION PL30
J 0
(-3075 5685);
DISPLAY 0.489362 (-3075 5685);
PAINT SKYBLUE (-3075 5685);
FORCEPROP 0 LAST $SEC 1
J 0
(-3075 5800);
DISPLAY 0.680851 (-3075 5800);
PAINT MONO (-3075 5800);
DISPLAY INVISIBLE (-3075 5800);
FORCEPROP 0 LAST CDS_SEC 1
J 0
(-3075 5800);
DISPLAY 1.021277 (-3075 5800);
DISPLAY INVISIBLE (-3075 5800);
FORCEPROP 0 LASTPIN (-3050 5500) $PN 1
J 2
(-3060 5510);
DISPLAY 0.489362 (-3060 5510);
PAINT MONO (-3060 5510);
FORCEPROP 0 LASTPIN (-2850 5500) $PN 2
J 0
(-2840 5510);
DISPLAY 0.489362 (-2840 5510);
PAINT MONO (-2840 5510);
FORCEPROP 1 LAST MATERIAL IND
J 0
(-3075 5580);
DISPLAY 0.489362 (-3075 5580);
PAINT SKYBLUE (-3075 5580);
FORCEPROP 2 LAST VALUE 50NH/86A
J 0
(-3075 5775);
DISPLAY 0.489362 (-3075 5775);
PAINT SKYBLUE (-3075 5775);
FORCEPROP 1 LAST PART_NUMBER CVA50^0MZ09
J 0
(-3075 5635);
DISPLAY 0.489362 (-3075 5635);
PAINT SKYBLUE (-3075 5635);
FORCEPROP 2 LAST PACK_TYPE SMLF
J 0
(-3075 5725);
DISPLAY 0.489362 (-3075 5725);
PAINT SKYBLUE (-3075 5725);
FORCEPROP 2 LAST CDS_LIB pure_quanta
J 0
(-2950 5525);
DISPLAY INVISIBLE (-2950 5525);
FORCEPROP 1 LAST NEEDS_NO_SIZE TRUE
J 0
(-2950 5525);
DISPLAY 0.468085 (-2950 5525);
PAINT GREEN (-2950 5525);
DISPLAY INVISIBLE (-2950 5525);
FORCEPROP 1 LAST PATH I24
J 0
(-2875 5580);
DISPLAY 0.723404 (-2875 5580);
PAINT GREEN (-2875 5580);
DISPLAY INVISIBLE (-2875 5580);
FORCEADD VCC_CORE..1
(-4075 5650);
FORCEPROP 3 LASTPIN (-4075 5600) SIG_NAME SW_P12V_STBY_PVDDCR_CPU0_P1_FLT\g
J 0
(-4065 5610);
DISPLAY 0.659574 (-4065 5610);
PAINT MONO (-4065 5610);
DISPLAY INVISIBLE (-4065 5610);
FORCEPROP 1 LAST HDL_POWER SW_P12V_STBY_PVDDCR_CPU0_P1_FLT
J 1
(-4075 5700);
DISPLAY 0.489362 (-4075 5700);
PAINT GREEN (-4075 5700);
FORCEPROP 2 LAST CDS_LIB pure_quanta_power
J 0
(-4075 5650);
DISPLAY INVISIBLE (-4075 5650);
FORCEPROP 1 LAST PATH I25
J 0
(-4025 5675);
DISPLAY 0.872340 (-4025 5675);
PAINT AQUA (-4025 5675);
DISPLAY INVISIBLE (-4025 5675);
FORCEADD Q_CAPP..1
(-3900 5325);
FORCEPROP 1 LAST LOCATION PC272
J 0
(-3850 5425);
DISPLAY 0.489362 (-3850 5425);
PAINT SKYBLUE (-3850 5425);
FORCEPROP 0 LAST $SEC 1
J 0
(-3850 5450);
DISPLAY 0.680851 (-3850 5450);
PAINT MONO (-3850 5450);
DISPLAY INVISIBLE (-3850 5450);
FORCEPROP 0 LAST CDS_SEC 1
J 0
(-3850 5450);
DISPLAY 1.021277 (-3850 5450);
DISPLAY INVISIBLE (-3850 5450);
FORCEPROP 1 LASTPIN (-3900 5425) $PN 1
J 0
(-3890 5410);
DISPLAY 0.489362 (-3890 5410);
PAINT MONO (-3890 5410);
FORCEPROP 1 LASTPIN (-3900 5225) $PN 2
J 0
(-3890 5210);
DISPLAY 0.489362 (-3890 5210);
PAINT MONO (-3890 5210);
FORCEPROP 1 LAST PART_NUMBER CC72204MD02
J 0
(-3850 5125);
DISPLAY 0.489362 (-3850 5125);
PAINT SKYBLUE (-3850 5125);
FORCEPROP 1 LAST PACK_TYPE THLF
J 0
(-3850 5175);
DISPLAY 0.489362 (-3850 5175);
PAINT SKYBLUE (-3850 5175);
FORCEPROP 1 LAST MATERIAL OSCON
J 0
(-3850 5225);
DISPLAY 0.489362 (-3850 5225);
PAINT SKYBLUE (-3850 5225);
FORCEPROP 1 LAST VOLTAGE 25V
J 0
(-3850 5275);
DISPLAY 0.489362 (-3850 5275);
PAINT SKYBLUE (-3850 5275);
FORCEPROP 1 LAST TOLERANCE 20%
J 0
(-3850 5325);
DISPLAY 0.489362 (-3850 5325);
PAINT SKYBLUE (-3850 5325);
FORCEPROP 1 LAST VALUE 220UF
J 0
(-3850 5375);
DISPLAY 0.489362 (-3850 5375);
PAINT SKYBLUE (-3850 5375);
FORCEPROP 2 LAST CDS_LIB pure_quanta
J 0
(-3900 5325);
DISPLAY INVISIBLE (-3900 5325);
FORCEPROP 1 LAST PATH I26
J 0
(-3850 5475);
DISPLAY 0.978723 (-3850 5475);
DISPLAY INVISIBLE (-3850 5475);
FORCEADD Q_CAPP..1
(-3525 5325);
FORCEPROP 1 LAST LOCATION PC273
J 0
(-3475 5425);
DISPLAY 0.489362 (-3475 5425);
PAINT SKYBLUE (-3475 5425);
FORCEPROP 0 LAST $SEC 1
J 0
(-3475 5450);
DISPLAY 0.680851 (-3475 5450);
PAINT MONO (-3475 5450);
DISPLAY INVISIBLE (-3475 5450);
FORCEPROP 0 LAST CDS_SEC 1
J 0
(-3475 5450);
DISPLAY 1.021277 (-3475 5450);
DISPLAY INVISIBLE (-3475 5450);
FORCEPROP 1 LASTPIN (-3525 5425) $PN 1
J 0
(-3515 5410);
DISPLAY 0.489362 (-3515 5410);
PAINT MONO (-3515 5410);
FORCEPROP 1 LASTPIN (-3525 5225) $PN 2
J 0
(-3515 5210);
DISPLAY 0.489362 (-3515 5210);
PAINT MONO (-3515 5210);
FORCEPROP 1 LAST PART_NUMBER CC72204MD02
J 0
(-3475 5125);
DISPLAY 0.489362 (-3475 5125);
PAINT SKYBLUE (-3475 5125);
FORCEPROP 1 LAST PACK_TYPE THLF
J 0
(-3475 5175);
DISPLAY 0.489362 (-3475 5175);
PAINT SKYBLUE (-3475 5175);
FORCEPROP 1 LAST MATERIAL OSCON
J 0
(-3475 5225);
DISPLAY 0.489362 (-3475 5225);
PAINT SKYBLUE (-3475 5225);
FORCEPROP 1 LAST VOLTAGE 25V
J 0
(-3475 5275);
DISPLAY 0.489362 (-3475 5275);
PAINT SKYBLUE (-3475 5275);
FORCEPROP 1 LAST VALUE 220UF
J 0
(-3475 5375);
DISPLAY 0.489362 (-3475 5375);
PAINT SKYBLUE (-3475 5375);
FORCEPROP 1 LAST TOLERANCE 20%
J 0
(-3475 5325);
DISPLAY 0.489362 (-3475 5325);
PAINT SKYBLUE (-3475 5325);
FORCEPROP 2 LAST CDS_LIB pure_quanta
J 0
(-3525 5325);
DISPLAY INVISIBLE (-3525 5325);
FORCEPROP 1 LAST PATH I27
J 0
(-3475 5475);
DISPLAY 0.978723 (-3475 5475);
DISPLAY INVISIBLE (-3475 5475);
FORCEADD Q_RES..2
(-7650 5350);
FORCEPROP 1 LAST LOCATION PR185
J 0
(-7600 5475);
DISPLAY 0.489362 (-7600 5475);
PAINT SKYBLUE (-7600 5475);
FORCEPROP 0 LAST $SEC 1
J 0
(-7600 5500);
DISPLAY 0.680851 (-7600 5500);
PAINT MONO (-7600 5500);
DISPLAY INVISIBLE (-7600 5500);
FORCEPROP 0 LAST CDS_SEC 1
J 0
(-7600 5500);
DISPLAY 1.021277 (-7600 5500);
DISPLAY INVISIBLE (-7600 5500);
FORCEPROP 1 LASTPIN (-7650 5450) $PN 1
J 0
(-7645 5412);
DISPLAY 0.489362 (-7645 5412);
PAINT MONO (-7645 5412);
FORCEPROP 1 LASTPIN (-7650 5250) $PN 2
J 0
(-7645 5260);
DISPLAY 0.489362 (-7645 5260);
PAINT MONO (-7645 5260);
FORCEPROP 1 LAST WATTAGE 1/16W
J 0
(-7600 5325);
DISPLAY 0.489362 (-7600 5325);
PAINT SKYBLUE (-7600 5325);
FORCEPROP 1 LAST MATERIAL CHIP
J 0
(-7600 5275);
DISPLAY 0.489362 (-7600 5275);
PAINT SKYBLUE (-7600 5275);
FORCEPROP 1 LAST TOLERANCE 1%
J 0
(-7600 5375);
DISPLAY 0.489362 (-7600 5375);
PAINT SKYBLUE (-7600 5375);
FORCEPROP 1 LAST VALUE 2.2
J 0
(-7600 5425);
DISPLAY 0.489362 (-7600 5425);
PAINT SKYBLUE (-7600 5425);
FORCEPROP 1 LAST PART_NUMBER CS-2202FB00
J 0
(-7600 5225);
DISPLAY 0.489362 (-7600 5225);
PAINT SKYBLUE (-7600 5225);
FORCEPROP 1 LAST PACK_TYPE 0402LF
J 0
(-7600 5175);
DISPLAY 0.489362 (-7600 5175);
PAINT SKYBLUE (-7600 5175);
FORCEPROP 2 LAST CDS_LIB pure_quanta
J 0
(-7650 5350);
DISPLAY INVISIBLE (-7650 5350);
FORCEPROP 1 LAST PATH I3
J 0
(-7600 5525);
DISPLAY 0.978723 (-7600 5525);
PAINT WHITE (-7600 5525);
DISPLAY INVISIBLE (-7600 5525);
FORCEADD VCC_CORE..1
(-2725 5650);
FORCEPROP 3 LASTPIN (-2725 5600) SIG_NAME P12V_STBY\g
J 0
(-2715 5610);
DISPLAY 0.659574 (-2715 5610);
PAINT MONO (-2715 5610);
DISPLAY INVISIBLE (-2715 5610);
FORCEPROP 1 LAST HDL_POWER P12V_STBY
J 1
(-2725 5700);
DISPLAY 0.489362 (-2725 5700);
PAINT GREEN (-2725 5700);
FORCEPROP 2 LAST CDS_LIB pure_quanta_power
J 0
(-2725 5650);
DISPLAY INVISIBLE (-2725 5650);
FORCEPROP 1 LAST PATH I30
J 0
(-2675 5675);
DISPLAY 0.872340 (-2675 5675);
PAINT AQUA (-2675 5675);
DISPLAY INVISIBLE (-2675 5675);
FORCEADD Q_INDUCTOR4P_14..1
(-3375 4325);
FORCEPROP 1 LAST LOCATION PL28
J 0
(-3600 4580);
DISPLAY 0.489362 (-3600 4580);
PAINT SKYBLUE (-3600 4580);
FORCEPROP 0 LAST $SEC 1
J 0
(-3600 4725);
DISPLAY 0.680851 (-3600 4725);
PAINT MONO (-3600 4725);
DISPLAY INVISIBLE (-3600 4725);
FORCEPROP 0 LAST CDS_SEC 1
J 0
(-3600 4725);
DISPLAY 1.021277 (-3600 4725);
DISPLAY INVISIBLE (-3600 4725);
FORCEPROP 0 LASTPIN (-3775 4450) $PN 1
J 2
(-3785 4460);
DISPLAY 0.489362 (-3785 4460);
PAINT MONO (-3785 4460);
FORCEPROP 0 LASTPIN (-3775 4200) $PN 2
J 2
(-3785 4210);
DISPLAY 0.489362 (-3785 4210);
PAINT MONO (-3785 4210);
FORCEPROP 0 LASTPIN (-2975 4200) $PN 3
J 0
(-2965 4210);
DISPLAY 0.489362 (-2965 4210);
PAINT MONO (-2965 4210);
FORCEPROP 0 LASTPIN (-2975 4450) $PN 4
J 0
(-2965 4460);
DISPLAY 0.489362 (-2965 4460);
PAINT MONO (-2965 4460);
FORCEPROP 2 LAST VALUE 150NH
J 0
(-3600 4625);
DISPLAY 0.489362 (-3600 4625);
PAINT SKYBLUE (-3600 4625);
FORCEPROP 2 LAST PART_TYPE SMLF
J 0
(-3600 4675);
DISPLAY 1.021277 (-3600 4675);
FORCEPROP 1 LAST MATERIAL IND
J 0
(-3600 4535);
DISPLAY 0.489362 (-3600 4535);
PAINT SKYBLUE (-3600 4535);
FORCEPROP 1 LAST PART_NUMBER CV+15^0TZ04
J 0
(-3600 4485);
DISPLAY 0.489362 (-3600 4485);
PAINT SKYBLUE (-3600 4485);
FORCEPROP 2 LAST CDS_LIB pure_quanta
J 0
(-3375 4325);
DISPLAY INVISIBLE (-3375 4325);
FORCEPROP 1 LAST NEEDS_NO_SIZE TRUE
J 0
(-3375 4325);
DISPLAY 0.468085 (-3375 4325);
PAINT GREEN (-3375 4325);
DISPLAY INVISIBLE (-3375 4325);
FORCEPROP 1 LAST PATH I31
J 0
(-3175 4480);
DISPLAY 0.723404 (-3175 4480);
PAINT GREEN (-3175 4480);
DISPLAY INVISIBLE (-3175 4480);
FORCEADD Q_CAP..1
(-1275 4275);
FORCEPROP 1 LAST LOCATION PC283_1
J 0
(-1225 4375);
DISPLAY 0.489362 (-1225 4375);
PAINT SKYBLUE (-1225 4375);
FORCEPROP 0 LAST $SEC 1
J 0
(-1225 4400);
DISPLAY 0.680851 (-1225 4400);
PAINT MONO (-1225 4400);
DISPLAY INVISIBLE (-1225 4400);
FORCEPROP 0 LAST CDS_SEC 1
J 0
(-1225 4400);
DISPLAY 1.021277 (-1225 4400);
DISPLAY INVISIBLE (-1225 4400);
FORCEPROP 1 LASTPIN (-1275 4375) $PN 1
J 0
(-1265 4355);
DISPLAY 0.489362 (-1265 4355);
PAINT MONO (-1265 4355);
FORCEPROP 1 LASTPIN (-1275 4175) $PN 2
J 0
(-1265 4155);
DISPLAY 0.489362 (-1265 4155);
PAINT MONO (-1265 4155);
FORCEPROP 1 LAST MATERIAL X6S
J 0
(-1225 4175);
DISPLAY 0.489362 (-1225 4175);
PAINT SKYBLUE (-1225 4175);
FORCEPROP 1 LAST TOLERANCE 20%
J 0
(-1225 4225);
DISPLAY 0.489362 (-1225 4225);
PAINT SKYBLUE (-1225 4225);
FORCEPROP 1 LAST VALUE 22UF
J 0
(-1225 4325);
DISPLAY 0.489362 (-1225 4325);
PAINT SKYBLUE (-1225 4325);
FORCEPROP 1 LAST VOLTAGE 4V
J 0
(-1225 4275);
DISPLAY 0.489362 (-1225 4275);
PAINT SKYBLUE (-1225 4275);
FORCEPROP 1 LAST PACK_TYPE 0805
J 0
(-1225 4125);
DISPLAY 0.489362 (-1225 4125);
PAINT SKYBLUE (-1225 4125);
FORCEPROP 2 LAST CDS_LIB pure_quanta
J 0
(-1275 4275);
DISPLAY INVISIBLE (-1275 4275);
FORCEPROP 1 LAST PATH I32
J 0
(-1225 4425);
DISPLAY 0.978723 (-1225 4425);
PAINT WHITE (-1225 4425);
DISPLAY INVISIBLE (-1225 4425);
FORCEPROP 1 LAST PART_NUMBER TMP_QCH622KMEA01
J 0
(-1225 4125);
DISPLAY 0.489362 (-1225 4125);
PAINT SKYBLUE (-1225 4125);
DISPLAY INVISIBLE (-1225 4125);
FORCEADD Q_CAP..1
(-1700 4275);
FORCEPROP 1 LAST LOCATION PC281_1
J 0
(-1650 4375);
DISPLAY 0.489362 (-1650 4375);
PAINT SKYBLUE (-1650 4375);
FORCEPROP 0 LAST $SEC 1
J 0
(-1650 4400);
DISPLAY 0.680851 (-1650 4400);
PAINT MONO (-1650 4400);
DISPLAY INVISIBLE (-1650 4400);
FORCEPROP 0 LAST CDS_SEC 1
J 0
(-1650 4400);
DISPLAY 1.021277 (-1650 4400);
DISPLAY INVISIBLE (-1650 4400);
FORCEPROP 1 LASTPIN (-1700 4375) $PN 1
J 0
(-1690 4355);
DISPLAY 0.489362 (-1690 4355);
PAINT MONO (-1690 4355);
FORCEPROP 1 LASTPIN (-1700 4175) $PN 2
J 0
(-1690 4155);
DISPLAY 0.489362 (-1690 4155);
PAINT MONO (-1690 4155);
FORCEPROP 1 LAST MATERIAL X6S
J 0
(-1650 4175);
DISPLAY 0.489362 (-1650 4175);
PAINT SKYBLUE (-1650 4175);
FORCEPROP 1 LAST TOLERANCE 20%
J 0
(-1650 4225);
DISPLAY 0.489362 (-1650 4225);
PAINT SKYBLUE (-1650 4225);
FORCEPROP 1 LAST VALUE 22UF
J 0
(-1650 4325);
DISPLAY 0.489362 (-1650 4325);
PAINT SKYBLUE (-1650 4325);
FORCEPROP 1 LAST PART_NUMBER TMP_QCH622KMEA01
J 0
(-1650 4125);
DISPLAY 0.489362 (-1650 4125);
PAINT SKYBLUE (-1650 4125);
FORCEPROP 1 LAST VOLTAGE 4V
J 0
(-1650 4275);
DISPLAY 0.489362 (-1650 4275);
PAINT SKYBLUE (-1650 4275);
FORCEPROP 1 LAST PACK_TYPE 0805
J 0
(-1650 4075);
DISPLAY 0.489362 (-1650 4075);
PAINT SKYBLUE (-1650 4075);
FORCEPROP 2 LAST CDS_LIB pure_quanta
J 0
(-1700 4275);
DISPLAY INVISIBLE (-1700 4275);
FORCEPROP 1 LAST PATH I33
J 0
(-1650 4425);
DISPLAY 0.978723 (-1650 4425);
PAINT WHITE (-1650 4425);
DISPLAY INVISIBLE (-1650 4425);
FORCEADD Q_CAP..1
(-2075 4275);
FORCEPROP 1 LAST LOCATION PC278
J 0
(-2025 4375);
DISPLAY 0.489362 (-2025 4375);
PAINT SKYBLUE (-2025 4375);
FORCEPROP 0 LAST $SEC 1
J 0
(-2025 4400);
DISPLAY 0.680851 (-2025 4400);
PAINT MONO (-2025 4400);
DISPLAY INVISIBLE (-2025 4400);
FORCEPROP 0 LAST CDS_SEC 1
J 0
(-2025 4400);
DISPLAY 1.021277 (-2025 4400);
DISPLAY INVISIBLE (-2025 4400);
FORCEPROP 1 LASTPIN (-2075 4375) $PN 1
J 0
(-2065 4355);
DISPLAY 0.489362 (-2065 4355);
PAINT MONO (-2065 4355);
FORCEPROP 1 LASTPIN (-2075 4175) $PN 2
J 0
(-2065 4155);
DISPLAY 0.489362 (-2065 4155);
PAINT MONO (-2065 4155);
FORCEPROP 1 LAST MATERIAL X7R
J 0
(-2025 4175);
DISPLAY 0.489362 (-2025 4175);
PAINT SKYBLUE (-2025 4175);
FORCEPROP 1 LAST TOLERANCE 10%
J 0
(-2025 4225);
DISPLAY 0.489362 (-2025 4225);
PAINT SKYBLUE (-2025 4225);
FORCEPROP 1 LAST VALUE 0.1UF
J 0
(-2025 4325);
DISPLAY 0.489362 (-2025 4325);
PAINT SKYBLUE (-2025 4325);
FORCEPROP 1 LAST PART_NUMBER CH4104K1B00
J 0
(-2025 4125);
DISPLAY 0.489362 (-2025 4125);
PAINT SKYBLUE (-2025 4125);
FORCEPROP 1 LAST VOLTAGE 25V
J 0
(-2025 4275);
DISPLAY 0.489362 (-2025 4275);
PAINT SKYBLUE (-2025 4275);
FORCEPROP 1 LAST PACK_TYPE 0402
J 0
(-2025 4075);
DISPLAY 0.489362 (-2025 4075);
PAINT SKYBLUE (-2025 4075);
FORCEPROP 2 LAST CDS_LIB pure_quanta
J 0
(-2075 4275);
DISPLAY INVISIBLE (-2075 4275);
FORCEPROP 1 LAST PATH I35
J 0
(-2025 4425);
DISPLAY 0.978723 (-2025 4425);
PAINT WHITE (-2025 4425);
DISPLAY INVISIBLE (-2025 4425);
FORCEADD UNIVERSAL_GND..1
(-975 3925);
FORCEPROP 3 LASTPIN (-975 3975) SIG_NAME GND\g
J 0
(-965 3985);
DISPLAY 0.659574 (-965 3985);
PAINT MONO (-965 3985);
DISPLAY INVISIBLE (-965 3985);
FORCEPROP 2 LAST CDS_LIB pure_quanta_power
J 0
(-975 3925);
DISPLAY INVISIBLE (-975 3925);
FORCEPROP 1 LAST PATH I36
J 0
(-900 3925);
DISPLAY 0.872340 (-900 3925);
PAINT AQUA (-900 3925);
DISPLAY INVISIBLE (-900 3925);
FORCEPROP 1 LAST HDL_POWER GND
J 1
(-950 3850);
DISPLAY 0.872340 (-950 3850);
PAINT GREEN (-950 3850);
DISPLAY INVISIBLE (-950 3850);
FORCEADD VCC_CORE..1
(-975 4600);
FORCEPROP 3 LASTPIN (-975 4550) SIG_NAME PVDDCR_CPU0_P1\g
J 0
(-965 4560);
DISPLAY 0.659574 (-965 4560);
PAINT MONO (-965 4560);
DISPLAY INVISIBLE (-965 4560);
FORCEPROP 1 LAST HDL_POWER PVDDCR_CPU0_P1
J 1
(-975 4650);
DISPLAY 0.489362 (-975 4650);
PAINT GREEN (-975 4650);
FORCEPROP 2 LAST CDS_LIB pure_quanta_power
J 0
(-975 4600);
DISPLAY INVISIBLE (-975 4600);
FORCEPROP 1 LAST PATH I37
J 0
(-925 4625);
DISPLAY 0.872340 (-925 4625);
PAINT AQUA (-925 4625);
DISPLAY INVISIBLE (-925 4625);
FORCEADD OFFPAGE..3
(-2425 4200);
FORCEPROP 2 LAST $XR0 187 
J 0
(-2181 4200);
DISPLAY 0.638298 (-2181 4200);
PAINT MONO (-2181 4200);
FORCEPROP 2 LAST PATH I39
J 2
(-2475 4275);
DISPLAY 1.021277 (-2475 4275);
DISPLAY INVISIBLE (-2475 4275);
FORCEPROP 1 LAST COMMENT_BODY TRUE
J 0
(-2475 4100);
DISPLAY 0.872340 (-2475 4100);
PAINT GREEN (-2475 4100);
DISPLAY INVISIBLE (-2475 4100);
FORCEPROP 2 LAST CDS_LIB standard
J 2
(-2425 4200);
DISPLAY INVISIBLE (-2425 4200);
FORCEPROP 1 LAST OFFPAGE TRUE
J 0
(-2100 4075);
DISPLAY 0.872340 (-2100 4075);
PAINT GREEN (-2100 4075);
DISPLAY INVISIBLE (-2100 4075);
FORCEADD Q_CAP..1
(-7650 4800);
FORCEPROP 1 LAST LOCATION PC256
J 0
(-7600 4900);
DISPLAY 0.489362 (-7600 4900);
PAINT SKYBLUE (-7600 4900);
FORCEPROP 0 LAST $SEC 1
J 0
(-7600 4925);
DISPLAY 0.680851 (-7600 4925);
PAINT MONO (-7600 4925);
DISPLAY INVISIBLE (-7600 4925);
FORCEPROP 0 LAST CDS_SEC 1
J 0
(-7600 4925);
DISPLAY 1.021277 (-7600 4925);
DISPLAY INVISIBLE (-7600 4925);
FORCEPROP 1 LASTPIN (-7650 4900) $PN 1
J 0
(-7640 4880);
DISPLAY 0.489362 (-7640 4880);
PAINT MONO (-7640 4880);
FORCEPROP 1 LASTPIN (-7650 4700) $PN 2
J 0
(-7640 4680);
DISPLAY 0.489362 (-7640 4680);
PAINT MONO (-7640 4680);
FORCEPROP 1 LAST MATERIAL X6S
J 0
(-7600 4700);
DISPLAY 0.489362 (-7600 4700);
PAINT SKYBLUE (-7600 4700);
FORCEPROP 1 LAST TOLERANCE 10%
J 0
(-7600 4750);
DISPLAY 0.489362 (-7600 4750);
PAINT SKYBLUE (-7600 4750);
FORCEPROP 1 LAST VALUE 2.2UF
J 0
(-7600 4850);
DISPLAY 0.489362 (-7600 4850);
PAINT SKYBLUE (-7600 4850);
FORCEPROP 1 LAST PART_NUMBER CH5222KEB01
J 0
(-7600 4650);
DISPLAY 0.489362 (-7600 4650);
PAINT SKYBLUE (-7600 4650);
FORCEPROP 1 LAST VOLTAGE 10V
J 0
(-7600 4800);
DISPLAY 0.489362 (-7600 4800);
PAINT SKYBLUE (-7600 4800);
FORCEPROP 1 LAST PACK_TYPE C0402
J 0
(-7600 4600);
DISPLAY 0.489362 (-7600 4600);
PAINT SKYBLUE (-7600 4600);
FORCEPROP 2 LAST CDS_LIB pure_quanta
J 0
(-7650 4800);
DISPLAY INVISIBLE (-7650 4800);
FORCEPROP 1 LAST PATH I4
J 0
(-7600 4950);
DISPLAY 0.978723 (-7600 4950);
PAINT WHITE (-7600 4950);
DISPLAY INVISIBLE (-7600 4950);
FORCEADD Q_RES..1
(-4375 3475);
FORCEPROP 1 LAST LOCATION PR191
J 0
(-4425 3525);
DISPLAY 0.489362 (-4425 3525);
PAINT SKYBLUE (-4425 3525);
FORCEPROP 0 LAST $SEC 1
J 0
(-4375 3550);
DISPLAY 0.680851 (-4375 3550);
PAINT MONO (-4375 3550);
DISPLAY INVISIBLE (-4375 3550);
FORCEPROP 0 LAST CDS_SEC 1
J 0
(-4375 3550);
DISPLAY 1.021277 (-4375 3550);
DISPLAY INVISIBLE (-4375 3550);
FORCEPROP 1 LASTPIN (-4475 3475) $PN 1
J 0
(-4463 3487);
DISPLAY 0.489362 (-4463 3487);
PAINT MONO (-4463 3487);
FORCEPROP 1 LASTPIN (-4275 3475) $PN 2
J 0
(-4313 3487);
DISPLAY 0.489362 (-4313 3487);
PAINT MONO (-4313 3487);
FORCEPROP 1 LAST PART_NUMBER CS00002JB38
J 0
(-4625 3425);
DISPLAY 0.489362 (-4625 3425);
PAINT SKYBLUE (-4625 3425);
FORCEPROP 1 LAST MATERIAL CHIP
J 0
(-4625 3375);
DISPLAY 0.489362 (-4625 3375);
PAINT SKYBLUE (-4625 3375);
FORCEPROP 1 LAST TOLERANCE 5%
J 0
(-4250 3500);
DISPLAY 0.489362 (-4250 3500);
PAINT SKYBLUE (-4250 3500);
FORCEPROP 1 LAST VALUE 0
J 2
(-4500 3500);
DISPLAY 0.489362 (-4500 3500);
PAINT SKYBLUE (-4500 3500);
FORCEPROP 1 LAST PACK_TYPE 0402LF
J 0
(-4275 3375);
DISPLAY 0.489362 (-4275 3375);
PAINT SKYBLUE (-4275 3375);
FORCEPROP 1 LAST WATTAGE 1/16W
J 0
(-4275 3425);
DISPLAY 0.489362 (-4275 3425);
PAINT SKYBLUE (-4275 3425);
FORCEPROP 2 LAST CDS_LIB pure_quanta
J 0
(-4375 3475);
DISPLAY INVISIBLE (-4375 3475);
FORCEPROP 1 LAST PATH I40
J 0
(-4425 3625);
DISPLAY 0.978723 (-4425 3625);
PAINT WHITE (-4425 3625);
DISPLAY INVISIBLE (-4425 3625);
FORCEADD OFFPAGE..1
(-8225 4350);
FORCEPROP 2 LAST $XR5 192 
J 0
(-9077 4350);
DISPLAY 0.638298 (-9077 4350);
PAINT MONO (-9077 4350);
FORCEPROP 2 LAST $XR4 191 
J 0
(-8957 4350);
DISPLAY 0.638298 (-8957 4350);
PAINT MONO (-8957 4350);
FORCEPROP 2 LAST $XR3 189 
J 0
(-8837 4350);
DISPLAY 0.638298 (-8837 4350);
PAINT MONO (-8837 4350);
FORCEPROP 2 LAST $XR2 188 
J 0
(-8717 4350);
DISPLAY 0.638298 (-8717 4350);
PAINT MONO (-8717 4350);
FORCEPROP 2 LAST $XR1 187 
J 0
(-8597 4350);
DISPLAY 0.638298 (-8597 4350);
PAINT MONO (-8597 4350);
FORCEPROP 2 LAST $XR0 186 
J 0
(-8477 4350);
DISPLAY 0.638298 (-8477 4350);
PAINT MONO (-8477 4350);
FORCEPROP 1 LAST OFFPAGE TRUE
J 0
(-7900 4225);
DISPLAY 0.872340 (-7900 4225);
PAINT GREEN (-7900 4225);
DISPLAY INVISIBLE (-7900 4225);
FORCEPROP 2 LAST PATH I41
J 0
(-8175 4425);
DISPLAY 1.021277 (-8175 4425);
DISPLAY INVISIBLE (-8175 4425);
FORCEPROP 1 LAST COMMENT_BODY TRUE
J 0
(-8100 4250);
DISPLAY 0.872340 (-8100 4250);
PAINT GREEN (-8100 4250);
DISPLAY INVISIBLE (-8100 4250);
FORCEPROP 2 LAST CDS_LIB standard
J 0
(-8225 4350);
DISPLAY INVISIBLE (-8225 4350);
FORCEADD ISL99390FRZTR5935..1
(-6150 1700);
FORCEPROP 1 LAST LOCATION PU26
J 0
(-6450 2575);
DISPLAY 0.489362 (-6450 2575);
PAINT SKYBLUE (-6450 2575);
FORCEPROP 0 LAST $SEC 1
J 0
(-6450 2725);
DISPLAY 0.680851 (-6450 2725);
PAINT MONO (-6450 2725);
DISPLAY INVISIBLE (-6450 2725);
FORCEPROP 2 LAST CDS_SEC 1
J 0
(-6450 2725);
DISPLAY 1.021277 (-6450 2725);
DISPLAY INVISIBLE (-6450 2725);
FORCEPROP 0 LASTPIN (-5750 1250) $PN 2
J 0
(-5740 1260);
DISPLAY 0.489362 (-5740 1260);
PAINT MONO (-5740 1260);
FORCEPROP 0 LASTPIN (-5750 2050) $PN 33
J 0
(-5740 2060);
DISPLAY 0.489362 (-5740 2060);
PAINT MONO (-5740 2060);
FORCEPROP 0 LASTPIN (-6600 1450) $PN 31
J 2
(-6610 1460);
DISPLAY 0.489362 (-6610 1460);
PAINT MONO (-6610 1460);
FORCEPROP 0 LASTPIN (-6600 1850) $PN 35
J 2
(-6610 1860);
DISPLAY 0.489362 (-6610 1860);
PAINT MONO (-6610 1860);
FORCEPROP 0 LASTPIN (-5750 1400) $PN 6
J 0
(-5740 1410);
DISPLAY 0.489362 (-5740 1410);
PAINT MONO (-5740 1410);
FORCEPROP 0 LASTPIN (-5750 1350) $PN 41
J 0
(-5740 1360);
DISPLAY 0.489362 (-5740 1360);
PAINT MONO (-5740 1360);
FORCEPROP 0 LASTPIN (-6600 1700) $PN 38
J 2
(-6610 1710);
DISPLAY 0.489362 (-6610 1710);
PAINT MONO (-6610 1710);
FORCEPROP 0 LASTPIN (-6600 1400) $PN 37
J 2
(-6610 1410);
DISPLAY 0.489362 (-6610 1410);
PAINT MONO (-6610 1410);
FORCEPROP 0 LASTPIN (-5750 1200) $PN 5
J 0
(-5740 1210);
DISPLAY 0.489362 (-5740 1210);
PAINT MONO (-5740 1210);
FORCEPROP 0 LASTPIN (-5750 1150) $PN 7_9-20_24
J 0
(-5740 1160);
DISPLAY 0.489362 (-5740 1160);
PAINT MONO (-5740 1160);
FORCEPROP 0 LASTPIN (-5750 1100) $PN 40
J 0
(-5740 1110);
DISPLAY 0.489362 (-5740 1110);
PAINT MONO (-5740 1110);
FORCEPROP 0 LASTPIN (-5750 1800) $PN 32
J 0
(-5740 1810);
DISPLAY 0.489362 (-5740 1810);
PAINT MONO (-5740 1810);
FORCEPROP 0 LASTPIN (-6600 2350) $PN 4
J 2
(-6610 2360);
DISPLAY 0.489362 (-6610 2360);
PAINT MONO (-6610 2360);
FORCEPROP 0 LASTPIN (-6600 1100) $PN 34
J 2
(-6610 1110);
DISPLAY 0.489362 (-6610 1110);
PAINT MONO (-6610 1110);
FORCEPROP 0 LASTPIN (-6600 1600) $PN 39
J 2
(-6610 1610);
DISPLAY 0.489362 (-6610 1610);
PAINT MONO (-6610 1610);
FORCEPROP 0 LASTPIN (-5750 1700) $PN 10_19
J 0
(-5740 1710);
DISPLAY 0.489362 (-5740 1710);
PAINT MONO (-5740 1710);
FORCEPROP 0 LASTPIN (-6600 1200) $PN 36
J 2
(-6610 1210);
DISPLAY 0.489362 (-6610 1210);
PAINT MONO (-6610 1210);
FORCEPROP 0 LASTPIN (-6600 2050) $PN 3
J 2
(-6610 2060);
DISPLAY 0.489362 (-6610 2060);
PAINT MONO (-6610 2060);
FORCEPROP 0 LASTPIN (-5750 2350) $PN 25_29
J 0
(-5740 2360);
DISPLAY 0.489362 (-5740 2360);
PAINT MONO (-5740 2360);
FORCEPROP 0 LASTPIN (-5750 2300) $PN 30
J 0
(-5740 2310);
DISPLAY 0.489362 (-5740 2310);
PAINT MONO (-5740 2310);
FORCEPROP 0 LASTPIN (-5750 1450) $PN 1
J 0
(-5740 1460);
DISPLAY 0.489362 (-5740 1460);
PAINT MONO (-5740 1460);
FORCEPROP 2 LAST PART_TYPE SMLF
J 0
(-6450 2675);
DISPLAY 1.021277 (-6450 2675);
FORCEPROP 1 LAST MATERIAL IC
J 0
(-6450 2425);
DISPLAY 0.489362 (-6450 2425);
PAINT SKYBLUE (-6450 2425);
FORCEPROP 2 LAST VALUE ISL99390FRZ-TR5935
J 0
(-6450 2625);
DISPLAY 0.489362 (-6450 2625);
PAINT SKYBLUE (-6450 2625);
FORCEPROP 1 LAST PART_NUMBER AL099390004
J 0
(-6450 2500);
DISPLAY 0.489362 (-6450 2500);
PAINT SKYBLUE (-6450 2500);
FORCEPROP 2 LAST CDS_LIB pure_quanta
J 0
(-6150 1700);
DISPLAY INVISIBLE (-6150 1700);
FORCEPROP 1 LAST CDS_LMAN_SYM_OUTLINE -300,700,250,-650
J 0
(-6150 1700);
DISPLAY 0.468085 (-6150 1700);
PAINT GREEN (-6150 1700);
DISPLAY INVISIBLE (-6150 1700);
FORCEPROP 1 LAST NEEDS_NO_SIZE TRUE
J 0
(-6150 1700);
DISPLAY 0.723404 (-6150 1700);
PAINT GREEN (-6150 1700);
DISPLAY INVISIBLE (-6150 1700);
FORCEPROP 1 LAST PATH I46
J 0
(-6150 1700);
DISPLAY 0.723404 (-6150 1700);
PAINT GREEN (-6150 1700);
DISPLAY INVISIBLE (-6150 1700);
FORCEADD VCC_CORE..1
(-1325 1850);
FORCEPROP 3 LASTPIN (-1325 1800) SIG_NAME PVDDCR_CPU0_P1\g
J 0
(-1315 1810);
DISPLAY 0.659574 (-1315 1810);
PAINT MONO (-1315 1810);
DISPLAY INVISIBLE (-1315 1810);
FORCEPROP 1 LAST HDL_POWER PVDDCR_CPU0_P1
J 1
(-1325 1900);
DISPLAY 0.489362 (-1325 1900);
PAINT GREEN (-1325 1900);
FORCEPROP 2 LAST CDS_LIB pure_quanta_power
J 0
(-1325 1850);
DISPLAY INVISIBLE (-1325 1850);
FORCEPROP 1 LAST PATH I47
J 0
(-1275 1875);
DISPLAY 0.872340 (-1275 1875);
PAINT AQUA (-1275 1875);
DISPLAY INVISIBLE (-1275 1875);
FORCEADD Q_CAP..1
(-1325 1525);
FORCEPROP 1 LAST LOCATION PC282_2
J 0
(-1275 1625);
DISPLAY 0.489362 (-1275 1625);
PAINT SKYBLUE (-1275 1625);
FORCEPROP 0 LAST $SEC 1
J 0
(-1275 1650);
DISPLAY 0.680851 (-1275 1650);
PAINT MONO (-1275 1650);
DISPLAY INVISIBLE (-1275 1650);
FORCEPROP 0 LAST CDS_SEC 1
J 0
(-1275 1650);
DISPLAY 1.021277 (-1275 1650);
DISPLAY INVISIBLE (-1275 1650);
FORCEPROP 1 LASTPIN (-1325 1625) $PN 1
J 0
(-1315 1605);
DISPLAY 0.489362 (-1315 1605);
PAINT MONO (-1315 1605);
FORCEPROP 1 LASTPIN (-1325 1425) $PN 2
J 0
(-1315 1405);
DISPLAY 0.489362 (-1315 1405);
PAINT MONO (-1315 1405);
FORCEPROP 1 LAST MATERIAL X6S
J 0
(-1275 1425);
DISPLAY 0.489362 (-1275 1425);
PAINT SKYBLUE (-1275 1425);
FORCEPROP 1 LAST TOLERANCE 20%
J 0
(-1275 1475);
DISPLAY 0.489362 (-1275 1475);
PAINT SKYBLUE (-1275 1475);
FORCEPROP 1 LAST VALUE 22UF
J 0
(-1275 1575);
DISPLAY 0.489362 (-1275 1575);
PAINT SKYBLUE (-1275 1575);
FORCEPROP 1 LAST PART_NUMBER TMP_QCH622KMEA01
J 0
(-1275 1375);
DISPLAY 0.489362 (-1275 1375);
PAINT SKYBLUE (-1275 1375);
FORCEPROP 1 LAST VOLTAGE 4V
J 0
(-1275 1525);
DISPLAY 0.489362 (-1275 1525);
PAINT SKYBLUE (-1275 1525);
FORCEPROP 1 LAST PACK_TYPE 0805
J 0
(-1275 1325);
DISPLAY 0.489362 (-1275 1325);
PAINT SKYBLUE (-1275 1325);
FORCEPROP 2 LAST CDS_LIB pure_quanta
J 0
(-1325 1525);
DISPLAY INVISIBLE (-1325 1525);
FORCEPROP 1 LAST PATH I48
J 0
(-1275 1675);
DISPLAY 0.978723 (-1275 1675);
PAINT WHITE (-1275 1675);
DISPLAY INVISIBLE (-1275 1675);
FORCEADD UNIVERSAL_GND..1
(-1325 1175);
FORCEPROP 3 LASTPIN (-1325 1225) SIG_NAME GND\g
J 0
(-1315 1235);
DISPLAY 0.659574 (-1315 1235);
PAINT MONO (-1315 1235);
DISPLAY INVISIBLE (-1315 1235);
FORCEPROP 2 LAST CDS_LIB pure_quanta_power
J 0
(-1325 1175);
DISPLAY INVISIBLE (-1325 1175);
FORCEPROP 1 LAST PATH I49
J 0
(-1250 1175);
DISPLAY 0.872340 (-1250 1175);
PAINT AQUA (-1250 1175);
DISPLAY INVISIBLE (-1250 1175);
FORCEPROP 1 LAST HDL_POWER GND
J 1
(-1300 1100);
DISPLAY 0.872340 (-1300 1100);
PAINT GREEN (-1300 1100);
DISPLAY INVISIBLE (-1300 1100);
FORCEADD UNIVERSAL_GND..1
(-7300 5100);
FORCEPROP 3 LASTPIN (-7300 5150) SIG_NAME GND\g
J 0
(-7290 5160);
DISPLAY 0.659574 (-7290 5160);
PAINT MONO (-7290 5160);
DISPLAY INVISIBLE (-7290 5160);
FORCEPROP 2 LAST CDS_LIB pure_quanta_power
J 0
(-7300 5100);
DISPLAY INVISIBLE (-7300 5100);
FORCEPROP 1 LAST PATH I5
J 0
(-7225 5100);
DISPLAY 0.872340 (-7225 5100);
PAINT AQUA (-7225 5100);
DISPLAY INVISIBLE (-7225 5100);
FORCEPROP 1 LAST HDL_POWER GND
J 1
(-7275 5025);
DISPLAY 0.872340 (-7275 5025);
PAINT GREEN (-7275 5025);
DISPLAY INVISIBLE (-7275 5025);
FORCEADD Q_CAP..1
(-1750 1525);
FORCEPROP 1 LAST LOCATION PC280_2
J 0
(-1700 1625);
DISPLAY 0.489362 (-1700 1625);
PAINT SKYBLUE (-1700 1625);
FORCEPROP 0 LAST $SEC 1
J 0
(-1700 1650);
DISPLAY 0.680851 (-1700 1650);
PAINT MONO (-1700 1650);
DISPLAY INVISIBLE (-1700 1650);
FORCEPROP 0 LAST CDS_SEC 1
J 0
(-1700 1650);
DISPLAY 1.021277 (-1700 1650);
DISPLAY INVISIBLE (-1700 1650);
FORCEPROP 1 LASTPIN (-1750 1625) $PN 1
J 0
(-1740 1605);
DISPLAY 0.489362 (-1740 1605);
PAINT MONO (-1740 1605);
FORCEPROP 1 LASTPIN (-1750 1425) $PN 2
J 0
(-1740 1405);
DISPLAY 0.489362 (-1740 1405);
PAINT MONO (-1740 1405);
FORCEPROP 1 LAST MATERIAL X6S
J 0
(-1700 1425);
DISPLAY 0.489362 (-1700 1425);
PAINT SKYBLUE (-1700 1425);
FORCEPROP 1 LAST TOLERANCE 20%
J 0
(-1700 1475);
DISPLAY 0.489362 (-1700 1475);
PAINT SKYBLUE (-1700 1475);
FORCEPROP 1 LAST VALUE 22UF
J 0
(-1700 1575);
DISPLAY 0.489362 (-1700 1575);
PAINT SKYBLUE (-1700 1575);
FORCEPROP 1 LAST PART_NUMBER TMP_QCH622KMEA01
J 0
(-1700 1375);
DISPLAY 0.489362 (-1700 1375);
PAINT SKYBLUE (-1700 1375);
FORCEPROP 1 LAST VOLTAGE 4V
J 0
(-1700 1525);
DISPLAY 0.489362 (-1700 1525);
PAINT SKYBLUE (-1700 1525);
FORCEPROP 1 LAST PACK_TYPE 0805
J 0
(-1700 1325);
DISPLAY 0.489362 (-1700 1325);
PAINT SKYBLUE (-1700 1325);
FORCEPROP 2 LAST CDS_LIB pure_quanta
J 0
(-1750 1525);
DISPLAY INVISIBLE (-1750 1525);
FORCEPROP 1 LAST PATH I50
J 0
(-1700 1675);
DISPLAY 0.978723 (-1700 1675);
PAINT WHITE (-1700 1675);
DISPLAY INVISIBLE (-1700 1675);
FORCEADD VCC_CORE..1
(-4250 2875);
FORCEPROP 3 LASTPIN (-4250 2825) SIG_NAME SW_P12V_STBY_PVDDCR_CPU0_P1_FLT\g
J 0
(-4240 2835);
DISPLAY 0.659574 (-4240 2835);
PAINT MONO (-4240 2835);
DISPLAY INVISIBLE (-4240 2835);
FORCEPROP 1 LAST HDL_POWER SW_P12V_STBY_PVDDCR_CPU0_P1_FLT
J 1
(-4250 2925);
DISPLAY 0.489362 (-4250 2925);
PAINT GREEN (-4250 2925);
FORCEPROP 2 LAST CDS_LIB pure_quanta_power
J 0
(-4250 2875);
DISPLAY INVISIBLE (-4250 2875);
FORCEPROP 1 LAST PATH I54
J 0
(-4200 2900);
DISPLAY 0.872340 (-4200 2900);
PAINT AQUA (-4200 2900);
DISPLAY INVISIBLE (-4200 2900);
FORCEADD UNIVERSAL_GND..1
(-4250 2225);
FORCEPROP 3 LASTPIN (-4250 2275) SIG_NAME GND\g
J 0
(-4240 2285);
DISPLAY 0.659574 (-4240 2285);
PAINT MONO (-4240 2285);
DISPLAY INVISIBLE (-4240 2285);
FORCEPROP 2 LAST CDS_LIB pure_quanta_power
J 0
(-4250 2225);
DISPLAY INVISIBLE (-4250 2225);
FORCEPROP 1 LAST PATH I56
J 0
(-4175 2225);
DISPLAY 0.872340 (-4175 2225);
PAINT AQUA (-4175 2225);
DISPLAY INVISIBLE (-4175 2225);
FORCEPROP 1 LAST HDL_POWER GND
J 1
(-4225 2150);
DISPLAY 0.872340 (-4225 2150);
PAINT GREEN (-4225 2150);
DISPLAY INVISIBLE (-4225 2150);
FORCEADD Q_CAP..1
(-4250 2575);
FORCEPROP 1 LAST LOCATION PC269_2
J 0
(-4200 2675);
DISPLAY 0.489362 (-4200 2675);
PAINT SKYBLUE (-4200 2675);
FORCEPROP 0 LAST $SEC 1
J 0
(-4200 2700);
DISPLAY 0.680851 (-4200 2700);
PAINT MONO (-4200 2700);
DISPLAY INVISIBLE (-4200 2700);
FORCEPROP 0 LAST CDS_SEC 1
J 0
(-4200 2700);
DISPLAY 1.021277 (-4200 2700);
DISPLAY INVISIBLE (-4200 2700);
FORCEPROP 1 LASTPIN (-4250 2675) $PN 1
J 0
(-4240 2655);
DISPLAY 0.489362 (-4240 2655);
PAINT MONO (-4240 2655);
FORCEPROP 1 LASTPIN (-4250 2475) $PN 2
J 0
(-4240 2455);
DISPLAY 0.489362 (-4240 2455);
PAINT MONO (-4240 2455);
FORCEPROP 1 LAST MATERIAL X6S
J 0
(-4200 2475);
DISPLAY 0.489362 (-4200 2475);
PAINT SKYBLUE (-4200 2475);
FORCEPROP 1 LAST VALUE 10UF
J 0
(-4200 2625);
DISPLAY 0.489362 (-4200 2625);
PAINT SKYBLUE (-4200 2625);
FORCEPROP 1 LAST PACK_TYPE C0805
J 0
(-4200 2375);
DISPLAY 0.489362 (-4200 2375);
PAINT SKYBLUE (-4200 2375);
FORCEPROP 1 LAST VOLTAGE 25V
J 0
(-4200 2575);
DISPLAY 0.489362 (-4200 2575);
PAINT SKYBLUE (-4200 2575);
FORCEPROP 1 LAST TOLERANCE 10%
J 0
(-4200 2525);
DISPLAY 0.489362 (-4200 2525);
PAINT SKYBLUE (-4200 2525);
FORCEPROP 1 LAST PART_NUMBER CH6104KEA00
J 0
(-4200 2425);
DISPLAY 0.489362 (-4200 2425);
PAINT SKYBLUE (-4200 2425);
FORCEPROP 2 LAST CDS_LIB pure_quanta
J 0
(-4250 2575);
DISPLAY INVISIBLE (-4250 2575);
FORCEPROP 1 LAST PATH I62
J 0
(-4200 2725);
DISPLAY 0.978723 (-4200 2725);
PAINT WHITE (-4200 2725);
DISPLAY INVISIBLE (-4200 2725);
FORCEADD Q_INDUCTOR4P_14..1
(-2925 1575);
FORCEPROP 1 LAST LOCATION PL29
J 0
(-3150 1830);
DISPLAY 0.489362 (-3150 1830);
PAINT SKYBLUE (-3150 1830);
FORCEPROP 0 LAST $SEC 1
J 0
(-3150 1975);
DISPLAY 0.680851 (-3150 1975);
PAINT MONO (-3150 1975);
DISPLAY INVISIBLE (-3150 1975);
FORCEPROP 0 LAST CDS_SEC 1
J 0
(-3150 1975);
DISPLAY 1.021277 (-3150 1975);
DISPLAY INVISIBLE (-3150 1975);
FORCEPROP 0 LASTPIN (-3325 1700) $PN 1
J 2
(-3335 1710);
DISPLAY 0.489362 (-3335 1710);
PAINT MONO (-3335 1710);
FORCEPROP 0 LASTPIN (-3325 1450) $PN 2
J 2
(-3335 1460);
DISPLAY 0.489362 (-3335 1460);
PAINT MONO (-3335 1460);
FORCEPROP 0 LASTPIN (-2525 1450) $PN 3
J 0
(-2515 1460);
DISPLAY 0.489362 (-2515 1460);
PAINT MONO (-2515 1460);
FORCEPROP 0 LASTPIN (-2525 1700) $PN 4
J 0
(-2515 1710);
DISPLAY 0.489362 (-2515 1710);
PAINT MONO (-2515 1710);
FORCEPROP 2 LAST PART_TYPE SMLF
J 0
(-3150 1925);
DISPLAY 1.021277 (-3150 1925);
FORCEPROP 1 LAST MATERIAL IND
J 0
(-3150 1785);
DISPLAY 0.489362 (-3150 1785);
PAINT SKYBLUE (-3150 1785);
FORCEPROP 2 LAST VALUE 150NH
J 0
(-3150 1875);
DISPLAY 0.489362 (-3150 1875);
PAINT SKYBLUE (-3150 1875);
FORCEPROP 1 LAST PART_NUMBER CV+15^0TZ04
J 0
(-3150 1735);
DISPLAY 0.489362 (-3150 1735);
PAINT SKYBLUE (-3150 1735);
FORCEPROP 2 LAST CDS_LIB pure_quanta
J 0
(-2925 1575);
DISPLAY INVISIBLE (-2925 1575);
FORCEPROP 1 LAST NEEDS_NO_SIZE TRUE
J 0
(-2925 1575);
DISPLAY 0.468085 (-2925 1575);
PAINT GREEN (-2925 1575);
DISPLAY INVISIBLE (-2925 1575);
FORCEPROP 1 LAST PATH I63
J 0
(-2725 1730);
DISPLAY 0.723404 (-2725 1730);
PAINT GREEN (-2725 1730);
DISPLAY INVISIBLE (-2725 1730);
FORCEADD Q_CAP..1
(-4550 2575);
FORCEPROP 1 LAST LOCATION PC267_2
J 0
(-4500 2675);
DISPLAY 0.489362 (-4500 2675);
PAINT SKYBLUE (-4500 2675);
FORCEPROP 0 LAST $SEC 1
J 0
(-4500 2700);
DISPLAY 0.680851 (-4500 2700);
PAINT MONO (-4500 2700);
DISPLAY INVISIBLE (-4500 2700);
FORCEPROP 0 LAST CDS_SEC 1
J 0
(-4500 2700);
DISPLAY 1.021277 (-4500 2700);
DISPLAY INVISIBLE (-4500 2700);
FORCEPROP 1 LASTPIN (-4550 2675) $PN 1
J 0
(-4540 2655);
DISPLAY 0.489362 (-4540 2655);
PAINT MONO (-4540 2655);
FORCEPROP 1 LASTPIN (-4550 2475) $PN 2
J 0
(-4540 2455);
DISPLAY 0.489362 (-4540 2455);
PAINT MONO (-4540 2455);
FORCEPROP 1 LAST PACK_TYPE C0805
J 0
(-4500 2375);
DISPLAY 0.489362 (-4500 2375);
PAINT SKYBLUE (-4500 2375);
FORCEPROP 1 LAST PART_NUMBER CH6104KEA00
J 0
(-4500 2425);
DISPLAY 0.489362 (-4500 2425);
PAINT SKYBLUE (-4500 2425);
FORCEPROP 1 LAST TOLERANCE 10%
J 0
(-4500 2525);
DISPLAY 0.489362 (-4500 2525);
PAINT SKYBLUE (-4500 2525);
FORCEPROP 1 LAST VOLTAGE 25V
J 0
(-4500 2575);
DISPLAY 0.489362 (-4500 2575);
PAINT SKYBLUE (-4500 2575);
FORCEPROP 1 LAST MATERIAL X6S
J 0
(-4500 2475);
DISPLAY 0.489362 (-4500 2475);
PAINT SKYBLUE (-4500 2475);
FORCEPROP 1 LAST VALUE 10UF
J 0
(-4500 2625);
DISPLAY 0.489362 (-4500 2625);
PAINT SKYBLUE (-4500 2625);
FORCEPROP 2 LAST CDS_LIB pure_quanta
J 0
(-4550 2575);
DISPLAY INVISIBLE (-4550 2575);
FORCEPROP 1 LAST PATH I64
J 0
(-4500 2725);
DISPLAY 0.978723 (-4500 2725);
PAINT WHITE (-4500 2725);
DISPLAY INVISIBLE (-4500 2725);
FORCEADD Q_CAP..1
(-4875 2575);
FORCEPROP 1 LAST LOCATION PC265_2
J 0
(-4825 2675);
DISPLAY 0.489362 (-4825 2675);
PAINT SKYBLUE (-4825 2675);
FORCEPROP 0 LAST $SEC 1
J 0
(-4825 2700);
DISPLAY 0.680851 (-4825 2700);
PAINT MONO (-4825 2700);
DISPLAY INVISIBLE (-4825 2700);
FORCEPROP 0 LAST CDS_SEC 1
J 0
(-4825 2700);
DISPLAY 1.021277 (-4825 2700);
DISPLAY INVISIBLE (-4825 2700);
FORCEPROP 1 LASTPIN (-4875 2675) $PN 1
J 0
(-4865 2655);
DISPLAY 0.489362 (-4865 2655);
PAINT MONO (-4865 2655);
FORCEPROP 1 LASTPIN (-4875 2475) $PN 2
J 0
(-4865 2455);
DISPLAY 0.489362 (-4865 2455);
PAINT MONO (-4865 2455);
FORCEPROP 1 LAST PACK_TYPE C0805
J 0
(-4825 2375);
DISPLAY 0.489362 (-4825 2375);
PAINT SKYBLUE (-4825 2375);
FORCEPROP 1 LAST MATERIAL X6S
J 0
(-4825 2475);
DISPLAY 0.489362 (-4825 2475);
PAINT SKYBLUE (-4825 2475);
FORCEPROP 1 LAST TOLERANCE 10%
J 0
(-4825 2525);
DISPLAY 0.489362 (-4825 2525);
PAINT SKYBLUE (-4825 2525);
FORCEPROP 1 LAST VALUE 10UF
J 0
(-4825 2625);
DISPLAY 0.489362 (-4825 2625);
PAINT SKYBLUE (-4825 2625);
FORCEPROP 1 LAST PART_NUMBER CH6104KEA00
J 0
(-4825 2425);
DISPLAY 0.489362 (-4825 2425);
PAINT SKYBLUE (-4825 2425);
FORCEPROP 1 LAST VOLTAGE 25V
J 0
(-4825 2575);
DISPLAY 0.489362 (-4825 2575);
PAINT SKYBLUE (-4825 2575);
FORCEPROP 2 LAST CDS_LIB pure_quanta
J 0
(-4875 2575);
DISPLAY INVISIBLE (-4875 2575);
FORCEPROP 1 LAST PATH I65
J 0
(-4825 2725);
DISPLAY 0.978723 (-4825 2725);
PAINT WHITE (-4825 2725);
DISPLAY INVISIBLE (-4825 2725);
FORCEADD Q_CAP..1
(-5200 2575);
FORCEPROP 1 LAST LOCATION PC263_2
J 0
(-5150 2675);
DISPLAY 0.489362 (-5150 2675);
PAINT SKYBLUE (-5150 2675);
FORCEPROP 0 LAST $SEC 1
J 0
(-5150 2700);
DISPLAY 0.680851 (-5150 2700);
PAINT MONO (-5150 2700);
DISPLAY INVISIBLE (-5150 2700);
FORCEPROP 0 LAST CDS_SEC 1
J 0
(-5150 2700);
DISPLAY 1.021277 (-5150 2700);
DISPLAY INVISIBLE (-5150 2700);
FORCEPROP 1 LASTPIN (-5200 2675) $PN 1
J 0
(-5190 2655);
DISPLAY 0.489362 (-5190 2655);
PAINT MONO (-5190 2655);
FORCEPROP 1 LASTPIN (-5200 2475) $PN 2
J 0
(-5190 2455);
DISPLAY 0.489362 (-5190 2455);
PAINT MONO (-5190 2455);
FORCEPROP 1 LAST PART_NUMBER CH5104KEB02
J 0
(-5150 2425);
DISPLAY 0.489362 (-5150 2425);
PAINT SKYBLUE (-5150 2425);
FORCEPROP 1 LAST PACK_TYPE C0402
J 0
(-5150 2375);
DISPLAY 0.489362 (-5150 2375);
PAINT SKYBLUE (-5150 2375);
FORCEPROP 1 LAST MATERIAL X6S
J 0
(-5150 2475);
DISPLAY 0.489362 (-5150 2475);
PAINT SKYBLUE (-5150 2475);
FORCEPROP 1 LAST TOLERANCE 10%
J 0
(-5150 2525);
DISPLAY 0.489362 (-5150 2525);
PAINT SKYBLUE (-5150 2525);
FORCEPROP 1 LAST VALUE 1UF
J 0
(-5150 2625);
DISPLAY 0.489362 (-5150 2625);
PAINT SKYBLUE (-5150 2625);
FORCEPROP 1 LAST VOLTAGE 25V
J 0
(-5150 2575);
DISPLAY 0.489362 (-5150 2575);
PAINT SKYBLUE (-5150 2575);
FORCEPROP 2 LAST CDS_LIB pure_quanta
J 0
(-5200 2575);
DISPLAY INVISIBLE (-5200 2575);
FORCEPROP 1 LAST PATH I66
J 0
(-5150 2725);
DISPLAY 0.978723 (-5150 2725);
PAINT WHITE (-5150 2725);
DISPLAY INVISIBLE (-5150 2725);
FORCEADD Q_CAP..1
(-3725 1925);
FORCEPROP 1 LAST LOCATION PC271
J 0
(-3675 2050);
DISPLAY 0.489362 (-3675 2050);
PAINT SKYBLUE (-3675 2050);
FORCEPROP 0 LAST $SEC 1
J 0
(-3675 2075);
DISPLAY 0.680851 (-3675 2075);
PAINT MONO (-3675 2075);
DISPLAY INVISIBLE (-3675 2075);
FORCEPROP 0 LAST CDS_SEC 1
J 0
(-3675 2075);
DISPLAY 1.021277 (-3675 2075);
DISPLAY INVISIBLE (-3675 2075);
FORCEPROP 1 LASTPIN (-3725 2025) $PN 1
J 0
(-3715 2005);
DISPLAY 0.489362 (-3715 2005);
PAINT MONO (-3715 2005);
FORCEPROP 1 LASTPIN (-3725 1825) $PN 2
J 0
(-3715 1805);
DISPLAY 0.489362 (-3715 1805);
PAINT MONO (-3715 1805);
FORCEPROP 1 LAST PACK_TYPE 0402
J 0
(-3675 1750);
DISPLAY 0.489362 (-3675 1750);
PAINT SKYBLUE (-3675 1750);
FORCEPROP 1 LAST MATERIAL X7R
J 0
(-3675 1850);
DISPLAY 0.489362 (-3675 1850);
PAINT SKYBLUE (-3675 1850);
FORCEPROP 1 LAST TOLERANCE 10%
J 0
(-3675 1900);
DISPLAY 0.489362 (-3675 1900);
PAINT SKYBLUE (-3675 1900);
FORCEPROP 1 LAST VALUE 0.22UF
J 0
(-3675 2000);
DISPLAY 0.489362 (-3675 2000);
PAINT SKYBLUE (-3675 2000);
FORCEPROP 1 LAST PART_NUMBER CH4223K1B00
J 0
(-3675 1800);
DISPLAY 0.489362 (-3675 1800);
PAINT SKYBLUE (-3675 1800);
FORCEPROP 1 LAST VOLTAGE 16V
J 0
(-3675 1950);
DISPLAY 0.489362 (-3675 1950);
PAINT SKYBLUE (-3675 1950);
FORCEPROP 2 LAST CDS_LIB pure_quanta
J 0
(-3725 1925);
DISPLAY INVISIBLE (-3725 1925);
FORCEPROP 1 LAST PATH I67
J 0
(-3675 2075);
DISPLAY 0.978723 (-3675 2075);
PAINT WHITE (-3675 2075);
DISPLAY INVISIBLE (-3675 2075);
FORCEADD Q_RES..1
(-4300 625);
FORCEPROP 1 LAST LOCATION PR192
J 0
(-4325 700);
DISPLAY 0.489362 (-4325 700);
PAINT SKYBLUE (-4325 700);
FORCEPROP 0 LAST $SEC 1
J 0
(-4300 700);
DISPLAY 0.680851 (-4300 700);
PAINT MONO (-4300 700);
DISPLAY INVISIBLE (-4300 700);
FORCEPROP 0 LAST CDS_SEC 1
J 0
(-4300 700);
DISPLAY 1.021277 (-4300 700);
DISPLAY INVISIBLE (-4300 700);
FORCEPROP 1 LASTPIN (-4400 625) $PN 1
J 0
(-4388 637);
DISPLAY 0.489362 (-4388 637);
PAINT MONO (-4388 637);
FORCEPROP 1 LASTPIN (-4200 625) $PN 2
J 0
(-4238 637);
DISPLAY 0.489362 (-4238 637);
PAINT MONO (-4238 637);
FORCEPROP 1 LAST WATTAGE 1/16W
J 0
(-4200 575);
DISPLAY 0.489362 (-4200 575);
PAINT SKYBLUE (-4200 575);
FORCEPROP 1 LAST MATERIAL CHIP
J 0
(-4550 525);
DISPLAY 0.489362 (-4550 525);
PAINT SKYBLUE (-4550 525);
FORCEPROP 1 LAST TOLERANCE 5%
J 0
(-4175 650);
DISPLAY 0.489362 (-4175 650);
PAINT SKYBLUE (-4175 650);
FORCEPROP 1 LAST VALUE 0
J 2
(-4425 650);
DISPLAY 0.489362 (-4425 650);
PAINT SKYBLUE (-4425 650);
FORCEPROP 1 LAST PART_NUMBER CS00002JB38
J 0
(-4550 575);
DISPLAY 0.489362 (-4550 575);
PAINT SKYBLUE (-4550 575);
FORCEPROP 1 LAST PACK_TYPE 0402LF
J 0
(-4200 525);
DISPLAY 0.489362 (-4200 525);
PAINT SKYBLUE (-4200 525);
FORCEPROP 2 LAST CDS_LIB pure_quanta
J 0
(-4300 625);
DISPLAY INVISIBLE (-4300 625);
FORCEPROP 1 LAST PATH I68
J 0
(-4350 775);
DISPLAY 0.978723 (-4350 775);
PAINT WHITE (-4350 775);
DISPLAY INVISIBLE (-4350 775);
FORCEADD UNIVERSAL_GND..1
(-7650 4600);
FORCEPROP 3 LASTPIN (-7650 4650) SIG_NAME GND\g
J 0
(-7640 4660);
DISPLAY 0.659574 (-7640 4660);
PAINT MONO (-7640 4660);
DISPLAY INVISIBLE (-7640 4660);
FORCEPROP 2 LAST CDS_LIB pure_quanta_power
J 0
(-7650 4600);
DISPLAY INVISIBLE (-7650 4600);
FORCEPROP 1 LAST PATH I7
J 0
(-7575 4600);
DISPLAY 0.872340 (-7575 4600);
PAINT AQUA (-7575 4600);
DISPLAY INVISIBLE (-7575 4600);
FORCEPROP 1 LAST HDL_POWER GND
J 1
(-7625 4525);
DISPLAY 0.872340 (-7625 4525);
PAINT GREEN (-7625 4525);
DISPLAY INVISIBLE (-7625 4525);
FORCEADD Q_RES..1
(-4725 2050);
FORCEPROP 1 LAST LOCATION PR190
J 0
(-4750 2100);
DISPLAY 0.489362 (-4750 2100);
PAINT SKYBLUE (-4750 2100);
FORCEPROP 0 LAST $SEC 1
J 0
(-4700 2125);
DISPLAY 0.680851 (-4700 2125);
PAINT MONO (-4700 2125);
DISPLAY INVISIBLE (-4700 2125);
FORCEPROP 0 LAST CDS_SEC 1
J 0
(-4700 2125);
DISPLAY 1.021277 (-4700 2125);
DISPLAY INVISIBLE (-4700 2125);
FORCEPROP 1 LASTPIN (-4825 2050) $PN 1
J 0
(-4813 2062);
DISPLAY 0.489362 (-4813 2062);
PAINT MONO (-4813 2062);
FORCEPROP 1 LASTPIN (-4625 2050) $PN 2
J 0
(-4663 2062);
DISPLAY 0.489362 (-4663 2062);
PAINT MONO (-4663 2062);
FORCEPROP 1 LAST TOLERANCE 1%
J 0
(-4600 2075);
DISPLAY 0.489362 (-4600 2075);
PAINT SKYBLUE (-4600 2075);
FORCEPROP 1 LAST MATERIAL CHIP
J 0
(-4975 1950);
DISPLAY 0.489362 (-4975 1950);
PAINT SKYBLUE (-4975 1950);
FORCEPROP 1 LAST WATTAGE 1/16W
J 0
(-4625 2000);
DISPLAY 0.489362 (-4625 2000);
PAINT SKYBLUE (-4625 2000);
FORCEPROP 1 LAST PACK_TYPE 0402LF
J 0
(-4625 1950);
DISPLAY 0.489362 (-4625 1950);
PAINT SKYBLUE (-4625 1950);
FORCEPROP 1 LAST VALUE 4.7
J 2
(-4850 2075);
DISPLAY 0.489362 (-4850 2075);
PAINT SKYBLUE (-4850 2075);
FORCEPROP 1 LAST PART_NUMBER CS-4702FB19
J 0
(-4975 2000);
DISPLAY 0.489362 (-4975 2000);
PAINT SKYBLUE (-4975 2000);
FORCEPROP 1 LAST PATH I71
J 0
(-4775 2200);
DISPLAY 0.978723 (-4775 2200);
PAINT WHITE (-4775 2200);
DISPLAY INVISIBLE (-4775 2200);
FORCEPROP 2 LAST CDS_LIB pure_quanta
J 0
(-4725 2050);
DISPLAY INVISIBLE (-4725 2050);
FORCEADD Q_RES..1
(-7325 1400);
FORCEPROP 1 LAST LOCATION PR188
J 0
(-7375 1450);
DISPLAY 0.489362 (-7375 1450);
PAINT SKYBLUE (-7375 1450);
FORCEPROP 0 LAST $SEC 1
J 0
(-7325 1475);
DISPLAY 0.680851 (-7325 1475);
PAINT MONO (-7325 1475);
DISPLAY INVISIBLE (-7325 1475);
FORCEPROP 0 LAST CDS_SEC 1
J 0
(-7325 1475);
DISPLAY 1.021277 (-7325 1475);
DISPLAY INVISIBLE (-7325 1475);
FORCEPROP 1 LASTPIN (-7425 1400) $PN 1
J 0
(-7413 1412);
DISPLAY 0.489362 (-7413 1412);
PAINT MONO (-7413 1412);
FORCEPROP 1 LASTPIN (-7225 1400) $PN 2
J 0
(-7263 1412);
DISPLAY 0.489362 (-7263 1412);
PAINT MONO (-7263 1412);
FORCEPROP 1 LAST WATTAGE 1/16W
J 0
(-7225 1300);
DISPLAY 0.489362 (-7225 1300);
PAINT SKYBLUE (-7225 1300);
FORCEPROP 1 LAST MATERIAL EMPTY
J 0
(-7625 1300);
DISPLAY 0.489362 (-7625 1300);
PAINT RED (-7625 1300);
FORCEPROP 1 LAST TOLERANCE 1%
J 0
(-7200 1425);
DISPLAY 0.489362 (-7200 1425);
PAINT SKYBLUE (-7200 1425);
FORCEPROP 1 LAST VALUE 8.87K
J 2
(-7425 1425);
DISPLAY 0.489362 (-7425 1425);
PAINT SKYBLUE (-7425 1425);
FORCEPROP 1 LAST PART_NUMBER CS28872FB01
J 0
(-7625 1350);
DISPLAY 0.489362 (-7625 1350);
PAINT SKYBLUE (-7625 1350);
FORCEPROP 1 LAST PACK_TYPE 0402LF
J 0
(-7225 1350);
DISPLAY 0.489362 (-7225 1350);
PAINT SKYBLUE (-7225 1350);
FORCEPROP 2 LAST CDS_LIB pure_quanta
J 0
(-7325 1400);
DISPLAY INVISIBLE (-7325 1400);
FORCEPROP 1 LAST PATH I75
J 0
(-7375 1550);
DISPLAY 0.978723 (-7375 1550);
PAINT WHITE (-7375 1550);
DISPLAY INVISIBLE (-7375 1550);
FORCEADD OFFPAGE..2
R 2
(-7325 4450);
FORCEPROP 2 LAST $XR0 186 
J 0
(-7610 4450);
DISPLAY 0.638298 (-7610 4450);
PAINT MONO (-7610 4450);
FORCEPROP 2 LAST PATH I8
J 2
(-7375 4525);
DISPLAY 1.021277 (-7375 4525);
DISPLAY INVISIBLE (-7375 4525);
FORCEPROP 1 LAST COMMENT_BODY TRUE
J 2
(-7280 4355);
DISPLAY 0.872340 (-7280 4355);
PAINT GREEN (-7280 4355);
DISPLAY INVISIBLE (-7280 4355);
FORCEPROP 2 LAST CDS_LIB standard
J 2
(-7325 4450);
DISPLAY INVISIBLE (-7325 4450);
FORCEPROP 1 LAST OFFPAGE TRUE
J 2
(-7650 4325);
DISPLAY 0.872340 (-7650 4325);
PAINT GREEN (-7650 4325);
DISPLAY INVISIBLE (-7650 4325);
FORCEADD OFFPAGE..2
R 2
(-7300 1700);
FORCEPROP 2 LAST $XR0 186 
J 0
(-7585 1700);
DISPLAY 0.638298 (-7585 1700);
PAINT MONO (-7585 1700);
FORCEPROP 2 LAST PATH I80
J 0
(-7250 1775);
DISPLAY 1.021277 (-7250 1775);
DISPLAY INVISIBLE (-7250 1775);
FORCEPROP 1 LAST COMMENT_BODY TRUE
J 2
(-7255 1605);
DISPLAY 0.872340 (-7255 1605);
PAINT GREEN (-7255 1605);
DISPLAY INVISIBLE (-7255 1605);
FORCEPROP 2 LAST CDS_LIB standard
J 2
(-7300 1700);
DISPLAY INVISIBLE (-7300 1700);
FORCEPROP 1 LAST OFFPAGE TRUE
J 2
(-7625 1575);
DISPLAY 0.872340 (-7625 1575);
PAINT GREEN (-7625 1575);
DISPLAY INVISIBLE (-7625 1575);
FORCEADD OFFPAGE..2
R 2
(-7275 1200);
FORCEPROP 2 LAST $XR3 186 
J 0
(-7770 1164);
DISPLAY 0.638298 (-7770 1164);
PAINT MONO (-7770 1164);
FORCEPROP 2 LAST $XR2 189 
J 0
(-7650 1164);
DISPLAY 0.638298 (-7650 1164);
PAINT MONO (-7650 1164);
FORCEPROP 2 LAST $XR1 188 
J 0
(-7530 1164);
DISPLAY 0.638298 (-7530 1164);
PAINT MONO (-7530 1164);
FORCEPROP 2 LAST $XR0 187 
J 0
(-7530 1200);
DISPLAY 0.638298 (-7530 1200);
PAINT MONO (-7530 1200);
FORCEPROP 2 LAST PATH I83
J 0
(-7225 1275);
DISPLAY 1.021277 (-7225 1275);
DISPLAY INVISIBLE (-7225 1275);
FORCEPROP 2 LAST CDS_LIB standard
J 0
(-7275 1200);
DISPLAY INVISIBLE (-7275 1200);
FORCEPROP 1 LAST COMMENT_BODY TRUE
J 2
(-7230 1105);
DISPLAY 0.872340 (-7230 1105);
PAINT GREEN (-7230 1105);
DISPLAY INVISIBLE (-7230 1105);
FORCEPROP 1 LAST OFFPAGE TRUE
J 2
(-7600 1075);
DISPLAY 0.872340 (-7600 1075);
PAINT GREEN (-7600 1075);
DISPLAY INVISIBLE (-7600 1075);
FORCEADD UNIVERSAL_GND..1
(-7650 1225);
FORCEPROP 3 LASTPIN (-7650 1275) SIG_NAME GND\g
J 0
(-7640 1285);
DISPLAY 0.659574 (-7640 1285);
PAINT MONO (-7640 1285);
DISPLAY INVISIBLE (-7640 1285);
FORCEPROP 2 LAST CDS_LIB pure_quanta_power
J 0
(-7650 1225);
DISPLAY INVISIBLE (-7650 1225);
FORCEPROP 1 LAST PATH I84
J 0
(-7575 1225);
DISPLAY 0.872340 (-7575 1225);
PAINT AQUA (-7575 1225);
DISPLAY INVISIBLE (-7575 1225);
FORCEPROP 1 LAST HDL_POWER GND
J 1
(-7625 1150);
DISPLAY 0.872340 (-7625 1150);
PAINT GREEN (-7625 1150);
DISPLAY INVISIBLE (-7625 1150);
FORCEADD UNIVERSAL_GND..1
(-7975 1150);
FORCEPROP 3 LASTPIN (-7975 1200) SIG_NAME GND\g
J 0
(-7965 1210);
DISPLAY 0.659574 (-7965 1210);
PAINT MONO (-7965 1210);
DISPLAY INVISIBLE (-7965 1210);
FORCEPROP 2 LAST CDS_LIB pure_quanta_power
J 0
(-7975 1150);
DISPLAY INVISIBLE (-7975 1150);
FORCEPROP 1 LAST PATH I85
J 0
(-7900 1150);
DISPLAY 0.872340 (-7900 1150);
PAINT AQUA (-7900 1150);
DISPLAY INVISIBLE (-7900 1150);
FORCEPROP 1 LAST HDL_POWER GND
J 1
(-7950 1075);
DISPLAY 0.872340 (-7950 1075);
PAINT GREEN (-7950 1075);
DISPLAY INVISIBLE (-7950 1075);
FORCEADD Q_CAP..1
(-7975 1425);
FORCEPROP 1 LAST LOCATION PC255_2
J 0
(-7925 1525);
DISPLAY 0.489362 (-7925 1525);
PAINT SKYBLUE (-7925 1525);
FORCEPROP 0 LAST $SEC 1
J 0
(-7925 1550);
DISPLAY 0.680851 (-7925 1550);
PAINT MONO (-7925 1550);
DISPLAY INVISIBLE (-7925 1550);
FORCEPROP 0 LAST CDS_SEC 1
J 0
(-7925 1550);
DISPLAY 1.021277 (-7925 1550);
DISPLAY INVISIBLE (-7925 1550);
FORCEPROP 1 LASTPIN (-7975 1525) $PN 1
J 0
(-7965 1505);
DISPLAY 0.489362 (-7965 1505);
PAINT MONO (-7965 1505);
FORCEPROP 1 LASTPIN (-7975 1325) $PN 2
J 0
(-7965 1305);
DISPLAY 0.489362 (-7965 1305);
PAINT MONO (-7965 1305);
FORCEPROP 1 LAST MATERIAL X7R
J 0
(-7925 1325);
DISPLAY 0.489362 (-7925 1325);
PAINT SKYBLUE (-7925 1325);
FORCEPROP 1 LAST TOLERANCE 10%
J 0
(-7925 1375);
DISPLAY 0.489362 (-7925 1375);
PAINT SKYBLUE (-7925 1375);
FORCEPROP 1 LAST VALUE 0.1UF
J 0
(-7925 1475);
DISPLAY 0.489362 (-7925 1475);
PAINT SKYBLUE (-7925 1475);
FORCEPROP 1 LAST PART_NUMBER CH4104K1B00
J 0
(-7925 1275);
DISPLAY 0.489362 (-7925 1275);
PAINT SKYBLUE (-7925 1275);
FORCEPROP 1 LAST VOLTAGE 25V
J 0
(-7925 1425);
DISPLAY 0.489362 (-7925 1425);
PAINT SKYBLUE (-7925 1425);
FORCEPROP 1 LAST PACK_TYPE 0402
J 0
(-7925 1225);
DISPLAY 0.489362 (-7925 1225);
PAINT SKYBLUE (-7925 1225);
FORCEPROP 2 LAST CDS_LIB pure_quanta
J 0
(-7975 1425);
DISPLAY INVISIBLE (-7975 1425);
FORCEPROP 1 LAST PATH I86
J 0
(-7925 1575);
DISPLAY 0.978723 (-7925 1575);
PAINT WHITE (-7925 1575);
DISPLAY INVISIBLE (-7925 1575);
FORCEADD OFFPAGE..1
(-8200 1600);
FORCEPROP 2 LAST $XR5 192 
J 0
(-9052 1600);
DISPLAY 0.638298 (-9052 1600);
PAINT MONO (-9052 1600);
FORCEPROP 2 LAST $XR4 191 
J 0
(-8932 1600);
DISPLAY 0.638298 (-8932 1600);
PAINT MONO (-8932 1600);
FORCEPROP 2 LAST $XR3 189 
J 0
(-8812 1600);
DISPLAY 0.638298 (-8812 1600);
PAINT MONO (-8812 1600);
FORCEPROP 2 LAST $XR2 188 
J 0
(-8692 1600);
DISPLAY 0.638298 (-8692 1600);
PAINT MONO (-8692 1600);
FORCEPROP 2 LAST $XR1 187 
J 0
(-8572 1600);
DISPLAY 0.638298 (-8572 1600);
PAINT MONO (-8572 1600);
FORCEPROP 2 LAST $XR0 186 
J 0
(-8452 1600);
DISPLAY 0.638298 (-8452 1600);
PAINT MONO (-8452 1600);
FORCEPROP 2 LAST PATH I87
J 0
(-8150 1675);
DISPLAY 1.021277 (-8150 1675);
DISPLAY INVISIBLE (-8150 1675);
FORCEPROP 1 LAST COMMENT_BODY TRUE
J 0
(-8075 1500);
DISPLAY 0.872340 (-8075 1500);
PAINT GREEN (-8075 1500);
DISPLAY INVISIBLE (-8075 1500);
FORCEPROP 1 LAST OFFPAGE TRUE
J 0
(-7875 1475);
DISPLAY 0.872340 (-7875 1475);
PAINT GREEN (-7875 1475);
DISPLAY INVISIBLE (-7875 1475);
FORCEPROP 2 LAST CDS_LIB standard
J 0
(-8200 1600);
DISPLAY INVISIBLE (-8200 1600);
FORCEADD UNIVERSAL_GND..1
(-5600 975);
FORCEPROP 3 LASTPIN (-5600 1025) SIG_NAME GND\g
J 0
(-5590 1035);
DISPLAY 0.659574 (-5590 1035);
PAINT MONO (-5590 1035);
DISPLAY INVISIBLE (-5590 1035);
FORCEPROP 2 LAST CDS_LIB pure_quanta_power
J 0
(-5600 975);
DISPLAY INVISIBLE (-5600 975);
FORCEPROP 1 LAST PATH I88
J 0
(-5525 975);
DISPLAY 0.872340 (-5525 975);
PAINT AQUA (-5525 975);
DISPLAY INVISIBLE (-5525 975);
FORCEPROP 1 LAST HDL_POWER GND
J 1
(-5575 900);
DISPLAY 0.872340 (-5575 900);
PAINT GREEN (-5575 900);
DISPLAY INVISIBLE (-5575 900);
FORCEADD OFFPAGE..1
(-7250 1100);
FORCEPROP 2 LAST $XR0 186 
J 0
(-7502 1100);
DISPLAY 0.638298 (-7502 1100);
PAINT MONO (-7502 1100);
FORCEPROP 1 LAST COMMENT_BODY TRUE
J 0
(-7125 1000);
DISPLAY 0.872340 (-7125 1000);
PAINT GREEN (-7125 1000);
DISPLAY INVISIBLE (-7125 1000);
FORCEPROP 1 LAST OFFPAGE TRUE
J 0
(-6925 975);
DISPLAY 0.872340 (-6925 975);
PAINT GREEN (-6925 975);
DISPLAY INVISIBLE (-6925 975);
FORCEPROP 2 LAST PATH I89
J 0
(-7200 1175);
DISPLAY 1.021277 (-7200 1175);
DISPLAY INVISIBLE (-7200 1175);
FORCEPROP 2 LAST CDS_LIB standard
J 2
(-7250 1100);
DISPLAY INVISIBLE (-7250 1100);
FORCEADD OFFPAGE..2
R 2
(-7300 3950);
FORCEPROP 2 LAST $XR3 186 
J 0
(-7825 3914);
DISPLAY 0.638298 (-7825 3914);
PAINT MONO (-7825 3914);
FORCEPROP 2 LAST $XR2 189 
J 0
(-7705 3914);
DISPLAY 0.638298 (-7705 3914);
PAINT MONO (-7705 3914);
FORCEPROP 2 LAST $XR1 188 
J 0
(-7585 3914);
DISPLAY 0.638298 (-7585 3914);
PAINT MONO (-7585 3914);
FORCEPROP 2 LAST $XR0 187 
J 0
(-7585 3950);
DISPLAY 0.638298 (-7585 3950);
PAINT MONO (-7585 3950);
FORCEPROP 2 LAST PATH I9
J 0
(-7250 4025);
DISPLAY 1.021277 (-7250 4025);
DISPLAY INVISIBLE (-7250 4025);
FORCEPROP 1 LAST COMMENT_BODY TRUE
J 2
(-7255 3855);
DISPLAY 0.872340 (-7255 3855);
PAINT GREEN (-7255 3855);
DISPLAY INVISIBLE (-7255 3855);
FORCEPROP 2 LAST CDS_LIB standard
J 0
(-7300 3950);
DISPLAY INVISIBLE (-7300 3950);
FORCEPROP 1 LAST OFFPAGE TRUE
J 2
(-7625 3825);
DISPLAY 0.872340 (-7625 3825);
PAINT GREEN (-7625 3825);
DISPLAY INVISIBLE (-7625 3825);
FORCEADD OFFPAGE..3
R 2
(-3825 1450);
FORCEPROP 2 LAST $XR0 187 
J 0
(-4105 1450);
DISPLAY 0.638298 (-4105 1450);
PAINT MONO (-4105 1450);
FORCEPROP 2 LAST PATH I91
J 2
(-4025 1525);
DISPLAY 1.021277 (-4025 1525);
DISPLAY INVISIBLE (-4025 1525);
FORCEPROP 1 LAST COMMENT_BODY TRUE
J 2
(-3775 1350);
DISPLAY 0.872340 (-3775 1350);
PAINT GREEN (-3775 1350);
DISPLAY INVISIBLE (-3775 1350);
FORCEPROP 2 LAST CDS_LIB standard
J 2
(-3825 1450);
DISPLAY INVISIBLE (-3825 1450);
FORCEPROP 1 LAST OFFPAGE TRUE
J 2
(-4150 1325);
DISPLAY 0.872340 (-4150 1325);
PAINT GREEN (-4150 1325);
DISPLAY INVISIBLE (-4150 1325);
FORCEADD Q_CAPP..1
(-2150 2900);
FORCEPROP 1 LAST LOCATION PC277
J 0
(-2100 3000);
DISPLAY 0.489362 (-2100 3000);
PAINT SKYBLUE (-2100 3000);
FORCEPROP 0 LAST $SEC 1
J 0
(-2100 3025);
DISPLAY 0.680851 (-2100 3025);
PAINT MONO (-2100 3025);
DISPLAY INVISIBLE (-2100 3025);
FORCEPROP 0 LAST CDS_SEC 1
J 0
(-2100 3025);
DISPLAY 1.021277 (-2100 3025);
DISPLAY INVISIBLE (-2100 3025);
FORCEPROP 1 LASTPIN (-2150 3000) $PN 1
J 0
(-2140 2985);
DISPLAY 0.489362 (-2140 2985);
PAINT MONO (-2140 2985);
FORCEPROP 1 LASTPIN (-2150 2800) $PN 2
J 0
(-2140 2785);
DISPLAY 0.489362 (-2140 2785);
PAINT MONO (-2140 2785);
FORCEPROP 1 LAST VOLTAGE 4V
J 0
(-2100 2850);
DISPLAY 0.489362 (-2100 2850);
PAINT SKYBLUE (-2100 2850);
FORCEPROP 1 LAST VALUE 220UF
J 0
(-2100 2950);
DISPLAY 0.489362 (-2100 2950);
PAINT SKYBLUE (-2100 2950);
FORCEPROP 1 LAST TOLERANCE 20%
J 0
(-2100 2900);
DISPLAY 0.489362 (-2100 2900);
PAINT SKYBLUE (-2100 2900);
FORCEPROP 1 LAST MATERIAL SPCAP
J 0
(-2100 2800);
DISPLAY 0.489362 (-2100 2800);
PAINT SKYBLUE (-2100 2800);
FORCEPROP 1 LAST PACK_TYPE SMLF
J 0
(-2100 2750);
DISPLAY 0.489362 (-2100 2750);
PAINT SKYBLUE (-2100 2750);
FORCEPROP 1 LAST PART_NUMBER CH122KM8801
J 0
(-2100 2700);
DISPLAY 0.489362 (-2100 2700);
PAINT SKYBLUE (-2100 2700);
FORCEPROP 1 LAST PATH I92
J 0
(-2100 3050);
DISPLAY 0.978723 (-2100 3050);
DISPLAY INVISIBLE (-2100 3050);
FORCEPROP 2 LAST CDS_LIB pure_quanta
J 0
(-2150 2900);
DISPLAY INVISIBLE (-2150 2900);
FORCEADD DNS..1
(-7950 5775);
PAINT RED (-7950 5775);
FORCEPROP 2 LAST CDS_LIB mstr_misc
J 0
(-7950 5775);
DISPLAY INVISIBLE (-7950 5775);
FORCEPROP 1 LAST COMMENT_BODY TRUE
R 1
J 0
(-7875 5550);
DISPLAY 0.872340 (-7875 5550);
PAINT GREEN (-7875 5550);
DISPLAY INVISIBLE (-7875 5550);
FORCEADD DNS..1
(-4875 4250);
PAINT RED (-4875 4250);
FORCEPROP 2 LAST CDS_LIB mstr_misc
J 0
(-4875 4250);
DISPLAY INVISIBLE (-4875 4250);
FORCEPROP 1 LAST COMMENT_BODY TRUE
R 1
J 0
(-4800 4025);
DISPLAY 0.872340 (-4800 4025);
PAINT GREEN (-4800 4025);
DISPLAY INVISIBLE (-4800 4025);
FORCEADD DNS..1
(-7350 4125);
PAINT RED (-7350 4125);
FORCEPROP 2 LAST CDS_LIB mstr_misc
J 0
(-7350 4125);
DISPLAY INVISIBLE (-7350 4125);
FORCEPROP 1 LAST COMMENT_BODY TRUE
R 1
J 0
(-7275 3900);
DISPLAY 0.872340 (-7275 3900);
PAINT GREEN (-7275 3900);
DISPLAY INVISIBLE (-7275 3900);
FORCEADD DNS..1
(-4725 1000);
PAINT RED (-4725 1000);
FORCEPROP 2 LAST CDS_LIB mstr_misc
J 0
(-4725 1000);
DISPLAY INVISIBLE (-4725 1000);
FORCEPROP 1 LAST COMMENT_BODY TRUE
R 1
J 0
(-4650 775);
DISPLAY 0.872340 (-4650 775);
PAINT GREEN (-4650 775);
DISPLAY INVISIBLE (-4650 775);
FORCEADD DNS..1
(-4875 3775);
PAINT RED (-4875 3775);
FORCEPROP 2 LAST CDS_LIB mstr_misc
J 0
(-4875 3775);
DISPLAY INVISIBLE (-4875 3775);
FORCEPROP 1 LAST COMMENT_BODY TRUE
R 1
J 0
(-4800 3550);
DISPLAY 0.872340 (-4800 3550);
PAINT GREEN (-4800 3550);
DISPLAY INVISIBLE (-4800 3550);
FORCEADD DNS..1
(-4725 1500);
PAINT RED (-4725 1500);
FORCEPROP 2 LAST CDS_LIB mstr_misc
J 0
(-4725 1500);
DISPLAY INVISIBLE (-4725 1500);
FORCEPROP 1 LAST COMMENT_BODY TRUE
R 1
J 0
(-4650 1275);
DISPLAY 0.872340 (-4650 1275);
PAINT GREEN (-4650 1275);
DISPLAY INVISIBLE (-4650 1275);
FORCEADD QUANTA_TITLE_BLOCK_C..1
(-475 -450);
FORCEPROP 0 LAST CDS_CON_LAST_MODIFIED Fri Mar 11 14:53:32 2022
J 0
(-2360 -435);
DISPLAY INVISIBLE (-2360 -435);
FORCEPROP 1 LAST CUSTOM_TXT_CDS <CON_LAST_MODIFIED>
J 0
(-2360 -435);
DISPLAY 0.978723 (-2360 -435);
FORCEPROP 2 LAST CUSTOM_TXT_CDS <XR_PAGE_TITLE>
J 0
(-8365 4800);
DISPLAY 0.638298 (-8365 4800);
PAINT PINK (-8365 4800);
DISPLAY INVISIBLE (-8365 4800);
FORCEPROP 1 LAST CUSTOM_TXT_CDS <NAME_2>
J 0
(-3650 -400);
FORCEPROP 1 LAST CUSTOM_TXT_CDS <NAME_1>
J 0
(-3650 -275);
FORCEPROP 1 LAST CUSTOM_TXT_CDS <Q_NUMBER>
J 0
(-1878 -347);
DISPLAY 1.212766 (-1878 -347);
FORCEPROP 1 LAST CUSTOM_TXT_CDS <Q_PROJ>
J 0
(-2857 -348);
DISPLAY 1.212766 (-2857 -348);
FORCEPROP 1 LAST CUSTOM_TXT_CDS <Q_REV>
J 0
(-659 -347);
DISPLAY 1.212766 (-659 -347);
FORCEPROP 1 LAST CUSTOM_TXT_CDS <CON_PAGE_NUM> OF <CON_TOTAL_PAGES>
J 0
(-921 -432);
DISPLAY 0.978723 (-921 -432);
FORCEPROP 1 LAST Q_DEPT BU9
J 1
(-4238 -401);
DISPLAY 1.957447 (-4238 -401);
PAINT GREEN (-4238 -401);
FORCEPROP 1 LAST Q_TITLE PVDDCR_CPU0_P1 VR PHASE 1&2
J 0
(-9800 -400);
DISPLAY 2.446809 (-9800 -400);
PAINT GREEN (-9800 -400);
FORCEPROP 2 LAST PAGE_BORDER TRUE
J 0
(-8365 4800);
DISPLAY 0.638298 (-8365 4800);
PAINT PINK (-8365 4800);
DISPLAY INVISIBLE (-8365 4800);
FORCEPROP 2 LAST CDS_LIB pure_quanta
J 0
(-475 -450);
DISPLAY INVISIBLE (-475 -450);
FORCEPROP 1 LAST CDS_LMAN_SYM_OUTLINE -9475,6775,100,-125
J 0
(-475 -450);
DISPLAY 0.468085 (-475 -450);
PAINT GREEN (-475 -450);
DISPLAY INVISIBLE (-475 -450);
FORCEPROP 1 LAST COMMENT_BODY TRUE
J 0
(-463 -463);
DISPLAY 0.978723 (-463 -463);
PAINT GREEN (-463 -463);
DISPLAY INVISIBLE (-463 -463);
FORCEPROP 2 LAST CDS_XR_PAGE_TITLE CR-187 : @T6G_MB_LIB.T6G(SCH_1):PAGE187
J 0
(-8365 4800);
DISPLAY 0.638298 (-8365 4800);
PAINT PINK (-8365 4800);
DISPLAY INVISIBLE (-8365 4800);
FORCEADD DNS..1
(-7325 1375);
PAINT RED (-7325 1375);
FORCEPROP 2 LAST CDS_LIB mstr_misc
J 0
(-7325 1375);
DISPLAY INVISIBLE (-7325 1375);
FORCEPROP 1 LAST COMMENT_BODY TRUE
R 1
J 0
(-7250 1150);
DISPLAY 0.872340 (-7250 1150);
PAINT GREEN (-7250 1150);
DISPLAY INVISIBLE (-7250 1150);
WIRE 16 -1 (-7625 1950)(-7625 1900);
WIRE 16 -1 (-7275 2525)(-7275 2400);
WIRE 16 -1 (-7450 4150)(-7675 4150);
WIRE 16 -1 (-7675 4150)(-7675 4025);
WIRE 16 -1 (-4850 3675)(-4850 3600);
WIRE 16 -1 (-4700 900)(-4700 825);
WIRE 16 -1 (-8300 5900)(-8300 5850);
WIRE 16 -1 (-7950 5900)(-7950 5850);
WIRE 16 -1 (-8000 4075)(-8000 3950);
WIRE 16 -1 (-7300 5275)(-7300 5150);
WIRE 16 -1 (-7650 4700)(-7650 4650);
WIRE 16 -1 (-7425 1400)(-7650 1400);
WIRE 16 -1 (-7650 1400)(-7650 1275);
WIRE 16 -1 (-7975 1325)(-7975 1200);
WIRE 16 -1 (-975 4550)(-975 4450);
WIRE 16 -1 (-975 4450)(-975 4375);
WIRE 16 -1 (-975 4450)(-1275 4450);
WIRE 16 -1 (-1275 4450)(-1275 4375);
WIRE 16 -1 (-1275 4450)(-1700 4450);
WIRE 16 -1 (-1700 4450)(-1700 4375);
WIRE 16 -1 (-1700 4450)(-2075 4450);
WIRE 16 -1 (-2075 4375)(-2075 4450);
WIRE 16 -1 (-2200 4450)(-2075 4450);
WIRE 16 -1 (-2975 4450)(-2200 4450);
WIRE 16 -1 (-2200 3475)(-2200 4450);
WIRE 16 -1 (-2200 3475)(-4275 3475);
WIRE 16 -1 (-5650 2350)(-5650 2300);
WIRE 16 -1 (-5650 2750)(-5650 2350);
WIRE 16 -1 (-5750 2350)(-5650 2350);
WIRE 16 -1 (-5650 2300)(-5750 2300);
WIRE 16 -1 (-5650 2750)(-5525 2750);
WIRE 16 -1 (-5525 2750)(-5200 2750);
WIRE 16 -1 (-5525 2675)(-5525 2750);
WIRE 16 -1 (-5200 2750)(-4875 2750);
WIRE 16 -1 (-5200 2675)(-5200 2750);
WIRE 16 -1 (-4875 2750)(-4550 2750);
WIRE 16 -1 (-4875 2675)(-4875 2750);
WIRE 16 -1 (-4550 2750)(-4250 2750);
WIRE 16 -1 (-4550 2750)(-4550 2675);
WIRE 16 -1 (-4250 2825)(-4250 2750);
WIRE 16 -1 (-4250 2750)(-4250 2675);
WIRE 17 273 (-1400 2325)(-1400 3425);
WIRE 17 273 (-3450 2325)(-1400 2325);
WIRE 17 273 (-1400 3425)(-3450 3425);
WIRE 17 273 (-3450 3425)(-3450 2325);
WIRE 16 -1 (-1850 2575)(-1850 2650);
WIRE 16 -1 (-1850 2800)(-1850 2650);
WIRE 16 -1 (-1850 2650)(-2150 2650);
WIRE 16 -1 (-2150 2650)(-2150 2800);
WIRE 16 -1 (-2475 2650)(-2150 2650);
WIRE 16 -1 (-2475 2800)(-2475 2650);
WIRE 16 -1 (-2800 2650)(-2475 2650);
WIRE 16 -1 (-2800 2800)(-2800 2650);
WIRE 16 -1 (-3150 2650)(-2800 2650);
WIRE 16 -1 (-3150 2800)(-3150 2650);
WIRE 16 -1 (-1325 1225)(-1325 1300);
WIRE 16 -1 (-1325 1425)(-1325 1300);
WIRE 16 -1 (-1325 1300)(-1750 1300);
WIRE 16 -1 (-1750 1425)(-1750 1300);
WIRE 16 -1 (-1950 1700)(-1950 625);
WIRE 16 -1 (-2525 1700)(-1950 1700);
WIRE 16 -1 (-1750 1700)(-1950 1700);
WIRE 16 -1 (-1950 625)(-4200 625);
WIRE 16 -1 (-1750 1700)(-1325 1700);
WIRE 16 -1 (-1750 1700)(-1750 1625);
WIRE 16 -1 (-1325 1800)(-1325 1700);
WIRE 16 -1 (-1325 1700)(-1325 1625);
WIRE 16 -1 (-4625 2050)(-3725 2050);
FORCEPROP 2 LAST SIG_NAME SW_PVDDCR_CPU0_P1_BOOT2_RC
J 2
(-3760 2060);
DISPLAY 0.489362 (-3760 2060);
FORCEPROP 2 LASTPROP $XRERR UNIQUE?
J 0
(-4000 2060);
DISPLAY 0.638298 (-4000 2060);
PAINT MONO (-4000 2060);
DISPLAY INVISIBLE (-4000 2060);
WIRE 16 -1 (-3725 2050)(-3725 2025);
WIRE 16 -1 (-4100 4575)(-4100 4550);
WIRE 16 -1 (-4100 4550)(-5775 4550);
FORCEPROP 2 LAST SIG_NAME SW_PVDDCR_CPU0_P1_PH1
J 0
(-5660 4560);
DISPLAY 0.489362 (-5660 4560);
FORCEPROP 2 LASTPROP $XRERR UNIQUE?
J 0
(-5900 4560);
DISPLAY 0.638298 (-5900 4560);
PAINT MONO (-5900 4560);
DISPLAY INVISIBLE (-5900 4560);
WIRE 16 -1 (-5775 4450)(-4850 4450);
FORCEPROP 2 LAST SIG_NAME SW_PVDDCR_CPU0_P1_SW1
J 0
(-5660 4460);
DISPLAY 0.489362 (-5660 4460);
FORCEPROP 2 LASTPROP $XRERR UNIQUE?
J 0
(-5900 4460);
DISPLAY 0.638298 (-5900 4460);
PAINT MONO (-5900 4460);
DISPLAY INVISIBLE (-5900 4460);
WIRE 16 -1 (-4850 4450)(-3775 4450);
WIRE 16 -1 (-4850 4350)(-4850 4450);
WIRE 16 -1 (-2725 5600)(-2725 5500);
WIRE 16 -1 (-2725 5500)(-2850 5500);
WIRE 16 -1 (-2975 4200)(-2475 4200);
FORCEPROP 2 LAST SIG_NAME IND_CPU0_P1_CPL1
J 0
(-2910 4210);
DISPLAY 0.489362 (-2910 4210);
WIRE 16 -1 (-975 3975)(-975 4050);
WIRE 16 -1 (-975 4175)(-975 4050);
WIRE 16 -1 (-975 4050)(-1275 4050);
WIRE 16 -1 (-1275 4175)(-1275 4050);
WIRE 16 -1 (-1275 4050)(-1700 4050);
WIRE 16 -1 (-1700 4175)(-1700 4050);
WIRE 16 -1 (-2075 4050)(-1700 4050);
WIRE 16 -1 (-2075 4050)(-2075 4175);
WIRE 16 -1 (-2200 1450)(-2525 1450);
FORCEPROP 2 LAST SIG_NAME IND_CPU0_P1_CPL2
J 0
(-2535 1460);
DISPLAY 0.489362 (-2535 1460);
WIRE 16 -1 (-4250 4200)(-3775 4200);
FORCEPROP 2 LAST SIG_NAME IND_CPU0_P1_CPL5
J 0
(-4210 4210);
DISPLAY 0.489362 (-4210 4210);
WIRE 16 -1 (-5775 4800)(-5025 4800);
FORCEPROP 2 LAST SIG_NAME SW_PVDDCR_CPU0_P1_BOOT1
J 0
(-5660 4810);
DISPLAY 0.489362 (-5660 4810);
FORCEPROP 2 LASTPROP $XRERR UNIQUE?
J 0
(-5900 4810);
DISPLAY 0.638298 (-5900 4810);
PAINT MONO (-5900 4810);
DISPLAY INVISIBLE (-5900 4810);
WIRE 16 -1 (-5775 4150)(-5250 4150);
FORCEPROP 2 LAST SIG_NAME NC_PVDDCR_CPU0_P1_GL1_1
J 0
(-5660 4160);
DISPLAY 0.489362 (-5660 4160);
FORCEPROP 2 LASTPROP $XRERR UNIQUE?
J 0
(-5220 4150);
DISPLAY 0.638298 (-5220 4150);
PAINT MONO (-5220 4150);
DISPLAY INVISIBLE (-5220 4150);
WIRE 16 -1 (-5775 4100)(-5250 4100);
FORCEPROP 2 LAST SIG_NAME NC_PVDDCR_CPU0_P1_GL2_1
J 0
(-5660 4110);
DISPLAY 0.489362 (-5660 4110);
FORCEPROP 2 LASTPROP $XRERR UNIQUE?
J 0
(-5220 4100);
DISPLAY 0.638298 (-5220 4100);
PAINT MONO (-5220 4100);
DISPLAY INVISIBLE (-5220 4100);
WIRE 16 -1 (-6625 4200)(-7075 4200);
FORCEPROP 2 LAST SIG_NAME NC_PVDDCR_CPU0_P1_DNC1
J 2
(-6685 4210);
DISPLAY 0.489362 (-6685 4210);
FORCEPROP 2 LASTPROP $XRERR UNIQUE?
J 0
(-7315 4200);
DISPLAY 0.638298 (-7315 4200);
PAINT MONO (-7315 4200);
DISPLAY INVISIBLE (-7315 4200);
WIRE 16 -1 (-6625 4450)(-7275 4450);
FORCEPROP 2 LAST SIG_NAME PVDDCR_CPU0_P1_IMON1
J 2
(-6685 4460);
DISPLAY 0.489362 (-6685 4460);
WIRE 16 -1 (-5750 2050)(-4825 2050);
FORCEPROP 2 LAST SIG_NAME SW_PVDDCR_CPU0_P1_BOOT2
J 0
(-5635 2060);
DISPLAY 0.489362 (-5635 2060);
FORCEPROP 2 LASTPROP $XRERR UNIQUE?
J 0
(-5875 2060);
DISPLAY 0.638298 (-5875 2060);
PAINT MONO (-5875 2060);
DISPLAY INVISIBLE (-5875 2060);
WIRE 16 -1 (-5775 3850)(-5600 3850);
WIRE 16 -1 (-5600 3850)(-5600 3900);
WIRE 16 -1 (-5600 3775)(-5600 3850);
WIRE 16 -1 (-5775 3900)(-5600 3900);
WIRE 16 -1 (-5600 3900)(-5600 3950);
WIRE 16 -1 (-5775 3950)(-5600 3950);
WIRE 16 -1 (-5600 4000)(-5600 3950);
WIRE 16 -1 (-5600 4000)(-5775 4000);
WIRE 16 -1 (-4700 1400)(-4700 1100);
FORCEPROP 2 LAST SIG_NAME SW_PVDDCR_CPU0_P1_SW2_RC
J 0
(-4660 1210);
DISPLAY 0.489362 (-4660 1210);
FORCEPROP 2 LASTPROP $XRERR UNIQUE?
J 0
(-4900 1210);
DISPLAY 0.638298 (-4900 1210);
PAINT MONO (-4900 1210);
DISPLAY INVISIBLE (-4900 1210);
WIRE 16 -1 (-5750 1100)(-5600 1100);
WIRE 16 -1 (-5600 1025)(-5600 1100);
WIRE 16 -1 (-5600 1100)(-5600 1150);
WIRE 16 -1 (-5750 1150)(-5600 1150);
WIRE 16 -1 (-5600 1150)(-5600 1200);
WIRE 16 -1 (-5750 1200)(-5600 1200);
WIRE 16 -1 (-5600 1250)(-5600 1200);
WIRE 16 -1 (-5600 1250)(-5750 1250);
WIRE 16 -1 (-5750 1400)(-5225 1400);
FORCEPROP 2 LAST SIG_NAME NC_PVDDCR_CPU0_P1_GL1_2
J 0
(-5635 1410);
DISPLAY 0.489362 (-5635 1410);
FORCEPROP 2 LASTPROP $XRERR UNIQUE?
J 0
(-5195 1400);
DISPLAY 0.638298 (-5195 1400);
PAINT MONO (-5195 1400);
DISPLAY INVISIBLE (-5195 1400);
WIRE 16 -1 (-5750 1350)(-5225 1350);
FORCEPROP 2 LAST SIG_NAME NC_PVDDCR_CPU0_P1_GL2_2
J 0
(-5635 1360);
DISPLAY 0.489362 (-5635 1360);
FORCEPROP 2 LASTPROP $XRERR UNIQUE?
J 0
(-5195 1350);
DISPLAY 0.638298 (-5195 1350);
PAINT MONO (-5195 1350);
DISPLAY INVISIBLE (-5195 1350);
WIRE 16 -1 (-6625 3950)(-7250 3950);
FORCEPROP 2 LAST SIG_NAME PVDDCR_CPU0_P1_TEMP0
J 2
(-6685 3960);
DISPLAY 0.489362 (-6685 3960);
WIRE 16 -1 (-6625 3850)(-7225 3850);
FORCEPROP 2 LAST SIG_NAME PVDDCR_CPU0_P1_PWM1
J 2
(-6685 3860);
DISPLAY 0.489362 (-6685 3860);
WIRE 16 -1 (-7625 2700)(-7625 2825);
WIRE 16 -1 (-7275 2825)(-7625 2825);
WIRE 16 -1 (-7625 2950)(-7625 2825);
WIRE 16 -1 (-6950 2825)(-7275 2825);
WIRE 16 -1 (-7275 2725)(-7275 2825);
WIRE 16 -1 (-6950 2350)(-6950 2825);
WIRE 16 -1 (-6950 2350)(-6600 2350);
WIRE 16 -1 (-7150 2050)(-7150 1850);
WIRE 16 -1 (-7150 2050)(-6600 2050);
WIRE 16 -1 (-7150 2225)(-7150 2050);
FORCEPROP 2 LAST SIG_NAME PVDDCR_CPU0_P1_VCC2
J 2
(-6685 2060);
DISPLAY 0.489362 (-6685 2060);
FORCEPROP 2 LASTPROP $XRERR UNIQUE?
J 0
(-6925 2060);
DISPLAY 0.638298 (-6925 2060);
PAINT MONO (-6925 2060);
DISPLAY INVISIBLE (-6925 2060);
WIRE 16 -1 (-7150 1850)(-6600 1850);
WIRE 16 -1 (-7625 2225)(-7150 2225);
WIRE 16 -1 (-7625 2500)(-7625 2225);
WIRE 16 -1 (-7625 2225)(-7625 2150);
WIRE 16 -1 (-6600 1450)(-7050 1450);
FORCEPROP 2 LAST SIG_NAME NC_PVDDCR_CPU0_P1_DNC2
J 2
(-6660 1460);
DISPLAY 0.489362 (-6660 1460);
FORCEPROP 2 LASTPROP $XRERR UNIQUE?
J 0
(-7290 1450);
DISPLAY 0.638298 (-7290 1450);
PAINT MONO (-7290 1450);
DISPLAY INVISIBLE (-7290 1450);
WIRE 16 -1 (-6600 1100)(-7200 1100);
FORCEPROP 2 LAST SIG_NAME PVDDCR_CPU0_P1_PWM2
J 2
(-6660 1110);
DISPLAY 0.489362 (-6660 1110);
WIRE 16 -1 (-6600 1200)(-7225 1200);
FORCEPROP 2 LAST SIG_NAME PVDDCR_CPU0_P1_TEMP0
J 2
(-6660 1210);
DISPLAY 0.489362 (-6660 1210);
WIRE 16 -1 (-6600 1700)(-7250 1700);
FORCEPROP 2 LAST SIG_NAME PVDDCR_CPU0_P1_IMON2
J 2
(-6660 1710);
DISPLAY 0.489362 (-6660 1710);
WIRE 16 -1 (-7975 1525)(-7975 1600);
WIRE 16 -1 (-6600 1600)(-7975 1600);
FORCEPROP 2 LAST SIG_NAME PVDDCR_CPU0_P1_VCCS
J 2
(-6660 1610);
DISPLAY 0.489362 (-6660 1610);
WIRE 16 -1 (-8150 1600)(-7975 1600);
WIRE 16 -1 (-7225 1400)(-6600 1400);
FORCEPROP 2 LAST SIG_NAME PVDDCR_CPU0_P1_LSET2
J 2
(-6660 1410);
DISPLAY 0.489362 (-6660 1410);
FORCEPROP 2 LASTPROP $XRERR UNIQUE?
J 0
(-6900 1410);
DISPLAY 0.638298 (-6900 1410);
PAINT MONO (-6900 1410);
DISPLAY INVISIBLE (-6900 1410);
WIRE 16 -1 (-4850 4150)(-4850 3875);
FORCEPROP 2 LAST SIG_NAME SW_PVDDCR_CPU0_P1_SW1_RC
J 0
(-4810 3985);
DISPLAY 0.489362 (-4810 3985);
FORCEPROP 2 LASTPROP $XRERR UNIQUE?
J 0
(-5050 3985);
DISPLAY 0.638298 (-5050 3985);
PAINT MONO (-5050 3985);
DISPLAY INVISIBLE (-5050 3985);
WIRE 16 -1 (-3775 1450)(-3325 1450);
FORCEPROP 2 LAST SIG_NAME IND_CPU0_P1_CPL1
J 0
(-3760 1460);
DISPLAY 0.489362 (-3760 1460);
WIRE 16 -1 (-5750 1700)(-4700 1700);
FORCEPROP 2 LAST SIG_NAME SW_PVDDCR_CPU0_P1_SW2
J 0
(-5635 1710);
DISPLAY 0.489362 (-5635 1710);
FORCEPROP 2 LASTPROP $XRERR UNIQUE?
J 0
(-5875 1710);
DISPLAY 0.638298 (-5875 1710);
PAINT MONO (-5875 1710);
DISPLAY INVISIBLE (-5875 1710);
WIRE 16 -1 (-4700 1700)(-3325 1700);
WIRE 16 -1 (-4700 1600)(-4700 1700);
WIRE 16 -1 (-5750 1450)(-5000 1450);
WIRE 16 -1 (-5000 625)(-5000 1450);
WIRE 16 -1 (-4400 625)(-5000 625);
FORCEPROP 2 LAST SIG_NAME PVDDCR_CPU0_P1_VOS2
J 0
(-5635 1475);
DISPLAY 0.489362 (-5635 1475);
FORCEPROP 2 LASTPROP $XRERR UNIQUE?
J 0
(-5875 1475);
DISPLAY 0.638298 (-5875 1475);
PAINT MONO (-5875 1475);
DISPLAY INVISIBLE (-5875 1475);
WIRE 16 -1 (-3725 1825)(-3725 1800);
WIRE 16 -1 (-3725 1800)(-5750 1800);
FORCEPROP 2 LAST SIG_NAME SW_PVDDCR_CPU0_P1_PH2
J 0
(-5635 1810);
DISPLAY 0.489362 (-5635 1810);
FORCEPROP 2 LASTPROP $XRERR UNIQUE?
J 0
(-5875 1810);
DISPLAY 0.638298 (-5875 1810);
PAINT MONO (-5875 1810);
DISPLAY INVISIBLE (-5875 1810);
WIRE 16 -1 (-5675 5050)(-5775 5050);
WIRE 16 -1 (-5675 5100)(-5675 5050);
WIRE 16 -1 (-5675 5500)(-5675 5100);
WIRE 16 -1 (-5775 5100)(-5675 5100);
WIRE 16 -1 (-5675 5500)(-5525 5500);
WIRE 16 -1 (-5525 5500)(-5200 5500);
WIRE 16 -1 (-5525 5425)(-5525 5500);
WIRE 16 -1 (-5200 5500)(-4875 5500);
WIRE 16 -1 (-5200 5425)(-5200 5500);
WIRE 16 -1 (-4875 5500)(-4550 5500);
WIRE 16 -1 (-4875 5425)(-4875 5500);
WIRE 16 -1 (-4550 5500)(-4250 5500);
WIRE 16 -1 (-4550 5500)(-4550 5425);
WIRE 16 -1 (-4075 5500)(-4250 5500);
WIRE 16 -1 (-4250 5500)(-4250 5425);
WIRE 16 -1 (-3900 5500)(-4075 5500);
WIRE 16 -1 (-4075 5600)(-4075 5500);
WIRE 16 -1 (-3900 5500)(-3525 5500);
WIRE 16 -1 (-3900 5500)(-3900 5425);
WIRE 16 -1 (-3050 5500)(-3525 5500);
WIRE 16 -1 (-3525 5500)(-3525 5425);
WIRE 16 -1 (-5525 5100)(-5525 5225);
WIRE 16 -1 (-5525 5100)(-5200 5100);
WIRE 16 -1 (-5200 5100)(-4875 5100);
WIRE 16 -1 (-5200 5225)(-5200 5100);
WIRE 16 -1 (-4875 5225)(-4875 5100);
WIRE 16 -1 (-4875 5100)(-4550 5100);
WIRE 16 -1 (-4550 5225)(-4550 5100);
WIRE 16 -1 (-4250 5100)(-4550 5100);
WIRE 16 -1 (-4050 5100)(-4250 5100);
WIRE 16 -1 (-4250 5225)(-4250 5100);
WIRE 16 -1 (-3900 5100)(-4050 5100);
WIRE 16 -1 (-4050 5100)(-4050 5025);
WIRE 16 -1 (-3900 5225)(-3900 5100);
WIRE 16 -1 (-3525 5100)(-3900 5100);
WIRE 16 -1 (-3525 5225)(-3525 5100);
WIRE 16 -1 (-4825 4800)(-4100 4800);
FORCEPROP 2 LAST SIG_NAME SW_PVDDCR_CPU0_P1_BOOT1_RC
J 2
(-4135 4810);
DISPLAY 0.489362 (-4135 4810);
FORCEPROP 2 LASTPROP $XRERR UNIQUE?
J 0
(-4375 4810);
DISPLAY 0.638298 (-4375 4810);
PAINT MONO (-4375 4810);
DISPLAY INVISIBLE (-4375 4810);
WIRE 16 -1 (-4100 4800)(-4100 4775);
WIRE 16 -1 (-7175 4600)(-6625 4600);
WIRE 16 -1 (-7175 4800)(-7175 4600);
WIRE 16 -1 (-7175 4800)(-6625 4800);
WIRE 16 -1 (-7175 4975)(-7175 4800);
FORCEPROP 2 LAST SIG_NAME PVDDCR_CPU0_P1_VCC1
J 2
(-6710 4810);
DISPLAY 0.489362 (-6710 4810);
FORCEPROP 2 LASTPROP $XRERR UNIQUE?
J 0
(-6950 4810);
DISPLAY 0.638298 (-6950 4810);
PAINT MONO (-6950 4810);
DISPLAY INVISIBLE (-6950 4810);
WIRE 16 -1 (-7650 4975)(-7175 4975);
WIRE 16 -1 (-7650 5250)(-7650 4975);
WIRE 16 -1 (-7650 4975)(-7650 4900);
WIRE 16 -1 (-3150 3000)(-3150 3100);
WIRE 16 -1 (-3150 3100)(-2800 3100);
WIRE 16 -1 (-2800 3100)(-2475 3100);
WIRE 16 -1 (-2800 3000)(-2800 3100);
WIRE 16 -1 (-2475 3000)(-2475 3100);
WIRE 16 -1 (-2475 3100)(-2150 3100);
WIRE 16 -1 (-2150 3000)(-2150 3100);
WIRE 16 -1 (-1850 3100)(-2150 3100);
WIRE 16 -1 (-1850 3150)(-1850 3100);
WIRE 16 -1 (-1850 3000)(-1850 3100);
WIRE 16 -1 (-6975 5100)(-6975 5575);
WIRE 16 -1 (-6975 5100)(-6625 5100);
WIRE 16 -1 (-6975 5575)(-7300 5575);
WIRE 16 -1 (-7300 5475)(-7300 5575);
WIRE 16 -1 (-7475 5575)(-7300 5575);
WIRE 16 -1 (-7475 5900)(-7475 5575);
WIRE 16 -1 (-7650 5575)(-7475 5575);
WIRE 16 -1 (-7650 5450)(-7650 5575);
WIRE 16 -1 (-7950 5575)(-7650 5575);
WIRE 16 -1 (-7950 5650)(-7950 5575);
WIRE 16 -1 (-8300 5575)(-7950 5575);
WIRE 16 -1 (-8300 5650)(-8300 5575);
WIRE 16 -1 (-8000 4275)(-8000 4350);
WIRE 16 -1 (-6625 4350)(-8000 4350);
FORCEPROP 2 LAST SIG_NAME PVDDCR_CPU0_P1_VCCS
J 2
(-6685 4360);
DISPLAY 0.489362 (-6685 4360);
WIRE 16 -1 (-8175 4350)(-8000 4350);
WIRE 16 -1 (-7250 4150)(-6625 4150);
FORCEPROP 2 LAST SIG_NAME PVDDCR_CPU0_P1_LSET1
J 2
(-6685 4160);
DISPLAY 0.489362 (-6685 4160);
FORCEPROP 2 LASTPROP $XRERR UNIQUE?
J 0
(-6925 4160);
DISPLAY 0.638298 (-6925 4160);
PAINT MONO (-6925 4160);
DISPLAY INVISIBLE (-6925 4160);
WIRE 16 -1 (-4475 3475)(-5075 3475);
FORCEPROP 2 LAST SIG_NAME PVDDCR_CPU0_P1_VOS1
J 0
(-5660 4225);
DISPLAY 0.489362 (-5660 4225);
FORCEPROP 2 LASTPROP $XRERR UNIQUE?
J 0
(-5900 4225);
DISPLAY 0.638298 (-5900 4225);
PAINT MONO (-5900 4225);
DISPLAY INVISIBLE (-5900 4225);
WIRE 16 -1 (-5075 3475)(-5075 4200);
WIRE 16 -1 (-5775 4200)(-5075 4200);
WIRE 16 -1 (-5525 2475)(-5525 2350);
WIRE 16 -1 (-5525 2350)(-5200 2350);
WIRE 16 -1 (-5200 2350)(-4875 2350);
WIRE 16 -1 (-5200 2475)(-5200 2350);
WIRE 16 -1 (-4875 2350)(-4550 2350);
WIRE 16 -1 (-4875 2475)(-4875 2350);
WIRE 16 -1 (-4250 2350)(-4550 2350);
WIRE 16 -1 (-4550 2475)(-4550 2350);
WIRE 16 -1 (-4250 2475)(-4250 2350);
WIRE 16 -1 (-4250 2350)(-4250 2275);
DOT 1 (-1850 2650);
DOT 1 (-2150 2650);
DOT 1 (-2475 2650);
DOT 1 (-2800 2650);
DOT 1 (-2800 3100);
DOT 1 (-4550 5500);
DOT 1 (-5650 2350);
DOT 1 (-7975 1600);
DOT 1 (-7150 2050);
DOT 1 (-7625 2225);
DOT 1 (-7625 2825);
DOT 1 (-7275 2825);
DOT 1 (-5600 1100);
DOT 1 (-5600 1150);
DOT 1 (-5600 1200);
DOT 1 (-4700 1700);
DOT 1 (-5525 2750);
DOT 1 (-5200 2750);
DOT 1 (-5600 3850);
DOT 1 (-5600 3950);
DOT 1 (-4875 2350);
DOT 1 (-4875 2750);
DOT 1 (-4550 2350);
DOT 1 (-4550 2750);
DOT 1 (-8000 4350);
DOT 1 (-7650 4975);
DOT 1 (-7175 4800);
DOT 1 (-7950 5575);
DOT 1 (-7650 5575);
DOT 1 (-7475 5575);
DOT 1 (-7300 5575);
DOT 1 (-5675 5100);
DOT 1 (-5525 5500);
DOT 1 (-5200 5500);
DOT 1 (-4850 4450);
DOT 1 (-4875 5100);
DOT 1 (-4550 5100);
DOT 1 (-4250 5100);
DOT 1 (-4875 5500);
DOT 1 (-4250 5500);
DOT 1 (-2150 3100);
DOT 1 (-1950 1700);
DOT 1 (-1750 1700);
DOT 1 (-1325 1300);
DOT 1 (-1325 1700);
DOT 1 (-1850 3100);
DOT 1 (-1700 4050);
DOT 1 (-1275 4050);
DOT 1 (-975 4050);
DOT 1 (-3900 5100);
DOT 1 (-4075 5500);
DOT 1 (-3900 5500);
DOT 1 (-2200 4450);
DOT 1 (-2075 4450);
DOT 1 (-1700 4450);
DOT 1 (-1275 4450);
DOT 1 (-975 4450);
DOT 1 (-3525 5500);
DOT 1 (-5200 5100);
DOT 1 (-5600 3900);
DOT 1 (-4050 5100);
DOT 1 (-4250 2350);
DOT 1 (-2475 3100);
DOT 1 (-5200 2350);
DOT 1 (-4250 2750);
FORCENOTE
MAIN=CH122KM8801
(-2575 2575) 0;
DISPLAY LEFT (-2575 2575);
DISPLAY 0.638298 (-2575 2575);
PAINT WHITE (-2575 2575);
FORCENOTE
ESR=9M OHM
(-2500 2550) 0;
DISPLAY LEFT (-2500 2550);
DISPLAY 0.638298 (-2500 2550);
PAINT WHITE (-2500 2550);
FORCENOTE
2ND=CH722KM8804
(-2575 2525) 0;
DISPLAY LEFT (-2575 2525);
DISPLAY 0.638298 (-2575 2525);
PAINT WHITE (-2575 2525);
FORCENOTE
7.3*4.3*1.9
(-2500 2500) 0;
DISPLAY LEFT (-2500 2500);
DISPLAY 0.638298 (-2500 2500);
PAINT WHITE (-2500 2500);
FORCENOTE
PR187,PR188,PR195,PR196,PR202,PR423 = CS00002JB38
(-9675 200) 0;
DISPLAY LEFT (-9675 200);
DISPLAY 1.021277 (-9675 200);
PAINT WHITE (-9675 200);
FORCENOTE
PR189,PR190,PR197,PR198,PR203,PR424 = CS00002JB38
(-9675 425) 0;
DISPLAY LEFT (-9675 425);
DISPLAY 1.021277 (-9675 425);
PAINT WHITE (-9675 425);
FORCENOTE
PC254_1,PC255_2,PC284_3,PC285_4,PC306_5,PC124_6 = EMPTY
(-9675 275) 0;
DISPLAY LEFT (-9675 275);
DISPLAY 1.021277 (-9675 275);
PAINT WHITE (-9675 275);
FORCENOTE
PR191,PR192,PR199,PR200,PR204,PR425 = EMPTY
(-9675 350) 0;
DISPLAY LEFT (-9675 350);
DISPLAY 1.021277 (-9675 350);
PAINT WHITE (-9675 350);
FORCENOTE
PU4,PU26,PU27,PU28,PU29,PU24 = AL021590000/TDA21590
(-9675 500) 0;
DISPLAY LEFT (-9675 500);
DISPLAY 1.021277 (-9675 500);
PAINT WHITE (-9675 500);
FORCENOTE
2ND SOURCE:INFENEON BOM
(-9675 575) 0;
DISPLAY LEFT (-9675 575);
DISPLAY 1.021277 (-9675 575);
PAINT WHITE (-9675 575);
FORCENOTE
PU4,PU26,PU27,PU28,PU29,PU24=AL099390004/ISL99390FRZ-TR5935
(-9675 725) 0;
DISPLAY LEFT (-9675 725);
DISPLAY 1.021277 (-9675 725);
PAINT WHITE (-9675 725);
FORCENOTE
3RD SOURCE:MPS BOM
(-9675 125) 0;
DISPLAY LEFT (-9675 125);
DISPLAY 1.021277 (-9675 125);
PAINT WHITE (-9675 125);
FORCENOTE
PU4,PU26,PU27,PU28,PU29,PU24=AL087000A02/MP87000GMJTH-C06A-Z
(-9675 50) 0;
DISPLAY LEFT (-9675 50);
DISPLAY 1.021277 (-9675 50);
PAINT WHITE (-9675 50);
FORCENOTE
PR335,PC254_1,PC255_2,PC284_3,PC285_4,PC306_5,PC124_6=EMPTY
(-9675 -25) 0;
DISPLAY LEFT (-9675 -25);
DISPLAY 1.021277 (-9675 -25);
PAINT WHITE (-9675 -25);
FORCENOTE
PR336,PR189,PR190,PR197,PR198,PR203,PR424=CS00002JB38
(-9675 -175) 0;
DISPLAY LEFT (-9675 -175);
DISPLAY 1.021277 (-9675 -175);
PAINT WHITE (-9675 -175);
FORCENOTE
MAIN SOURCE:RENESAS BOM
(-9675 800) 0;
DISPLAY LEFT (-9675 800);
DISPLAY 1.021277 (-9675 800);
PAINT WHITE (-9675 800);
FORCENOTE
ISAT:70A@100C
(-2525 1975) 0;
DISPLAY LEFT (-2525 1975);
DISPLAY 0.638298 (-2525 1975);
PAINT WHITE (-2525 1975);
FORCENOTE
DCR=1-4,0.105M OHM
(-2525 1875) 0;
DISPLAY LEFT (-2525 1875);
DISPLAY 0.638298 (-2525 1875);
PAINT WHITE (-2525 1875);
FORCENOTE
DCR=2-3,0.27M OHM
(-2525 1825) 0;
DISPLAY LEFT (-2525 1825);
DISPLAY 0.638298 (-2525 1825);
PAINT WHITE (-2525 1825);
FORCENOTE
2ND=CV+15^0TZ01
(-2525 1775) 0;
DISPLAY LEFT (-2525 1775);
DISPLAY 0.638298 (-2525 1775);
PAINT WHITE (-2525 1775);
FORCENOTE
3RD=CVA50^0MZ08
(-3150 5175) 0;
DISPLAY LEFT (-3150 5175);
DISPLAY 0.638298 (-3150 5175);
PAINT WHITE (-3150 5175);
FORCENOTE
2ND=CVA50^0MZ07
(-3150 5225) 0;
DISPLAY LEFT (-3150 5225);
DISPLAY 0.638298 (-3150 5225);
PAINT WHITE (-3150 5225);
FORCENOTE
DCR=0.09M OHM
(-3150 5275) 0;
DISPLAY LEFT (-3150 5275);
DISPLAY 0.638298 (-3150 5275);
PAINT WHITE (-3150 5275);
FORCENOTE
2ND=CV+15^0TZ01
(-2975 4525) 0;
DISPLAY LEFT (-2975 4525);
DISPLAY 0.638298 (-2975 4525);
PAINT WHITE (-2975 4525);
FORCENOTE
6.0*6.1*7.0
(-3150 5325) 0;
DISPLAY LEFT (-3150 5325);
DISPLAY 0.638298 (-3150 5325);
PAINT WHITE (-3150 5325);
FORCENOTE
DCR=2-3,0.27M OHM
(-2975 4575) 0;
DISPLAY LEFT (-2975 4575);
DISPLAY 0.638298 (-2975 4575);
PAINT WHITE (-2975 4575);
FORCENOTE
DCR=1-4,0.105M OHM
(-2975 4625) 0;
DISPLAY LEFT (-2975 4625);
DISPLAY 0.638298 (-2975 4625);
PAINT WHITE (-2975 4625);
FORCENOTE
11.0*7.5*12.5
(-2975 4675) 0;
DISPLAY LEFT (-2975 4675);
DISPLAY 0.638298 (-2975 4675);
PAINT WHITE (-2975 4675);
FORCENOTE
ISAT:70A@100C
(-2975 4725) 0;
DISPLAY LEFT (-2975 4725);
DISPLAY 0.638298 (-2975 4725);
PAINT WHITE (-2975 4725);
FORCENOTE
PGL6303.151HLT
(-2975 4775) 0;
DISPLAY LEFT (-2975 4775);
DISPLAY 0.638298 (-2975 4775);
PAINT WHITE (-2975 4775);
FORCENOTE
PGL6303.151HLT
(-2525 2025) 0;
DISPLAY LEFT (-2525 2025);
DISPLAY 0.638298 (-2525 2025);
PAINT WHITE (-2525 2025);
FORCENOTE
ISAT:70A@100C
(-3150 5375) 0;
DISPLAY LEFT (-3150 5375);
DISPLAY 0.638298 (-3150 5375);
PAINT WHITE (-3150 5375);
FORCENOTE
PVDDCR_CPU0_P1_PHASE1
(-6750 5850) 0;
DISPLAY LEFT (-6750 5850);
DISPLAY 1.595745 (-6750 5850);
PAINT WHITE (-6750 5850);
FORCENOTE
PG2292.500HLT
(-3150 5425) 0;
DISPLAY LEFT (-3150 5425);
DISPLAY 0.638298 (-3150 5425);
PAINT WHITE (-3150 5425);
FORCENOTE
PR191,PR192,PR199,PR200,PR204,PR425=EMPTY
(-9675 -100) 0;
DISPLAY LEFT (-9675 -100);
DISPLAY 1.021277 (-9675 -100);
PAINT WHITE (-9675 -100);
FORCENOTE
BOM NOTE
(-9675 925) 0;
DISPLAY LEFT (-9675 925);
DISPLAY 1.021277 (-9675 925);
PAINT WHITE (-9675 925);
FORCENOTE
8*11.5
(-3800 4950) 0;
DISPLAY LEFT (-3800 4950);
DISPLAY 0.638298 (-3800 4950);
PAINT WHITE (-3800 4950);
FORCENOTE
ESR=16M OHM
(-3800 5050) 0;
DISPLAY LEFT (-3800 5050);
DISPLAY 0.638298 (-3800 5050);
PAINT WHITE (-3800 5050);
FORCENOTE
IRIPPLE:4.65A
(-3800 5000) 0;
DISPLAY LEFT (-3800 5000);
DISPLAY 0.638298 (-3800 5000);
PAINT WHITE (-3800 5000);
FORCENOTE
2ND=CC72204MD01
(-3800 4900) 0;
DISPLAY LEFT (-3800 4900);
DISPLAY 0.638298 (-3800 4900);
PAINT WHITE (-3800 4900);
FORCENOTE
3RD=CC72204MD03
(-3800 4850) 0;
DISPLAY LEFT (-3800 4850);
DISPLAY 0.638298 (-3800 4850);
PAINT WHITE (-3800 4850);
FORCENOTE
11.0*7.5*12.5
(-2525 1925) 0;
DISPLAY LEFT (-2525 1925);
DISPLAY 0.638298 (-2525 1925);
PAINT WHITE (-2525 1925);
FORCENOTE
PVDDCR_CPU0_P1_PHASE2
(-6725 3025) 0;
DISPLAY LEFT (-6725 3025);
DISPLAY 1.595745 (-6725 3025);
PAINT WHITE (-6725 3025);
QUIT
